FILE_TYPE = MULTI_PHYS_TABLE;

PART 'Q_LED'

{========================================================================================}
:COLOR                      | PACK_TYPE | MANUF_PN                    | MATERIAL | PART_NUMBER       = STANDARD        | LIFECYCLE      | PART_NUMBER       | JEDEC_TYPE                     | CLASS | DESCRIPTION                                                           | COMPONENT_TYPE | LEAD_LENGTH | LPID | DAY        ;
{========================================================================================}
 'GREEN'                    | 'THLF'    | 'L-710A8CB/1ZGT'            | 'IC'     | 'BEGR0175D00'(!)  = 'End of Design' | 'Comp-Approve' | 'BEGR0175D00'     |'LED_5514207XA'| 'IC'  | 'LED DIP(2P) GREEN(L-710A8CB/1ZGT)'                                   | ''             | ''          | ''   | ''        
 'GREEN'                    | 'THLF'    | 'L-710A8CB/1ZGT'            | 'EMPTY'  | 'BEGR0175D00'(!)  = 'End of Design' | 'Comp-Approve' | 'BEGR0175D00'     |'LED_5514207XA'| 'IO'  | 'LED DIP(2P) GREEN(L-710A8CB/1ZGT)'                                   | ''             | ''          | ''   | ''        
 'YELLOW'                   | 'THLF'    | 'L-710A8EW/1YD'             | 'IC'     | 'BEYL0052D00'(!)  = 'End of Design' | 'Comp-Approve' | 'BEYL0052D00'     |'LED_710A8EW'| 'IC'  | 'LED DIP(2P) YELLOW(L-710A8EW/1YD)'                                   | ''             | ''          | ''   | ''        
 'YELLOW'                   | 'THLF'    | 'L-710A8EW/1YD'             | 'EMPTY'  | 'BEYL0052D00'(!)  = 'End of Design' | 'Comp-Approve' | 'BEYL0052D00'     |'LED_710A8EW'| 'IO'  | 'LED DIP(2P) YELLOW(L-710A8EW/1YD)'                                   | ''             | ''          | ''   | ''        
 'GREEN'                    | 'SMLF'    | 'KPHM-1608SGC-T'            | 'IC'     | 'BEGR0203Z00'(!)  = 'End of Design' | 'Comp-Approve' | 'BEGR0203Z00'     |'LED_19217'| 'IC'  | 'LED SMD(2P) BRIGHT GREEN KPHM-1608SGC-T'                             | ''             | ''          | ''   | ''        
 'GREEN'                    | 'SMLF'    | 'KPHM-1608SGC-T'            | 'EMPTY'  | 'BEGR0203Z00'(!)  = 'End of Design' | 'Comp-Approve' | 'BEGR0203Z00'     |'LED_19217'| 'IO'  | 'LED SMD(2P) BRIGHT GREEN KPHM-1608SGC-T'                             | ''             | ''          | ''   | ''        
 'YELLOW'                   | 'SMLF'    | 'KPHM-1608YC-T'             | 'IC'     | 'BEYL0071Z01'(!)  = 'End of Design' | 'Comp-Approve' | 'BEYL0071Z01'     |'LED_19217'| 'IC'  | 'LED SMD(2P) YELLOW KPHM-1608YC-T'                                    | ''             | ''          | ''   | ''        
 'YELLOW'                   | 'SMLF'    | 'KPHM-1608YC-T'             | 'EMPTY'  | 'BEYL0071Z01'(!)  = 'End of Design' | 'Comp-Approve' | 'BEYL0071Z01'     |'LED_19217'| 'IO'  | 'LED SMD(2P) YELLOW KPHM-1608YC-T'                                    | ''             | ''          | ''   | ''        
 'BLUE'                     | 'SMLF'    | 'KPHM-1608QBC-C'            | 'IC'     | 'BEBL0101Z00'(!)  = 'End of Design' | 'Comp-Approve' | 'BEBL0101Z00'     |'LED_19217'| 'IC'  | 'LED SMD(2P) BLUE KPHM-1608QBC-C'                                     | ''             | ''          | ''   | ''        
 'BLUE'                     | 'SMLF'    | 'KPHM-1608QBC-C'            | 'EMPTY'  | 'BEBL0101Z00'(!)  = 'End of Design' | 'Comp-Approve' | 'BEBL0101Z00'     |'LED_19217'| 'IO'  | 'LED SMD(2P) BLUE KPHM-1608QBC-C'                                     | ''             | ''          | ''   | ''        
 'RED'                      | 'SMLF'    | 'KPHM-1608EC-T'             | 'IC'     | 'BERD0054Z00'(!)  = 'End of Design' | 'Comp-Approve' | 'BERD0054Z00'     |'LED_19217'| 'IC'  | 'LED SMD(2P) RED KPHM-1608EC-T'                                       | ''             | ''          | ''   | ''        
 'RED'                      | 'SMLF'    | 'KPHM-1608EC-T'             | 'EMPTY'  | 'BERD0054Z00'(!)  = 'End of Design' | 'Comp-Approve' | 'BERD0054Z00'     |'LED_19217'| 'IO'  | 'LED SMD(2P) RED KPHM-1608EC-T'                                       | ''             | ''          | ''   | ''        
 'LED YELLOW'               | 'SMLF'    | '19-21UYC/S530-A2/TR8 '     | 'IC'     | 'BEYL0016Z08'(!)  = 'End of Design' | 'Comp-Approve' | 'BEYL0016Z08'     |'LED_1921'| 'IC'  | 'LED SMD(2P)YEL(19-21UYC/S530-A2/TR8)  '                              | ''             | ''          | ''   | '20100709'
 'LED YELLOW'               | 'SMLF'    | '19-21UYC/S530-A2/TR8 '     | 'EMPTY'  | 'BEYL0016Z08'(!)  = 'End of Design' | 'Comp-Approve' | 'BEYL0016Z08'     |'LED_1921'| 'IO'  | 'LED SMD(2P)YEL(19-21UYC/S530-A2/TR8)  '                              | ''             | ''          | ''   | '20100709'
 'GREEN'                    | 'SMLF'    | '19-21VGC/TR8'              | 'IC'     | 'BEGR0037Z04'(!)  = 'End of Design' | 'End of Life'  | 'BEGR0037Z04'     |'LED_1921_EOL'| 'IC'  | 'LED SMD 2P GREEN(1.6*0.8*0.8)VGC/TR8'                                | ''             | ''          | ''   | ''        
 'GREEN'                    | 'SMLF'    | '19-21VGC/TR8'              | 'EMPTY'  | 'BEGR0037Z04'(!)  = 'End of Design' | 'End of Life'  | 'BEGR0037Z04'     |'LED_1921_EOL'| 'IO'  | 'LED SMD 2P GREEN(1.6*0.8*0.8)VGC/TR8'                                | ''             | ''          | ''   | ''        
 'GREEN'                    | 'SMLF'    | 'KPHM-1608VGC-A'            | 'IC'     | 'BEGR0237Z00'(!)  = 'End of Design' | 'Comp-Approve' | 'BEGR0237Z00'     |'LED_19217'| 'IC'  | 'LED SMD(2P) GREEN KPHM-1608VGC-A'                                    | ''             | ''          | ''   | ''        
 'GREEN'                    | 'SMLF'    | 'KPHM-1608VGC-A'            | 'EMPTY'  | 'BEGR0237Z00'(!)  = 'End of Design' | 'Comp-Approve' | 'BEGR0237Z00'     |'LED_19217'| 'IO'  | 'LED SMD(2P) GREEN KPHM-1608VGC-A'                                    | ''             | ''          | ''   | ''        
 'BLUE'                     | 'THLF'    | 'L-1384AD/1PBD-A-DTS'       | 'IC'     | 'BEBL0104D01'(!)  = 'End of Design' | 'Comp-Approve' | 'BEBL0104D01'     |'LED_L1384AD'| 'IC'  | 'LED DIP(2P)BLUE(L-1384AD/1PBD-A-DTS)'                                | ''             | ''          | ''   | ''        
 'BLUE'                     | 'THLF'    | 'L-1384AD/1PBD-A-DTS'       | 'EMPTY'  | 'BEBL0104D01'(!)  = 'End of Design' | 'Comp-Approve' | 'BEBL0104D01'     |'LED_L1384AD'| 'IO'  | 'LED DIP(2P)BLUE(L-1384AD/1PBD-A-DTS)'                                | ''             | ''          | ''   | ''        
 'BLUE'                     | 'THLF'    | 'L-710A8EW/1QBD-C'          | 'IC'     | 'BEBL0150D00'(!)  = 'End of Design' | 'Comp-Approve' | 'BEBL0150D00'     |'LED_710A8EW'| 'IC'  | 'LED DIP 2P BLUE (L-710A8EW/1QBD-C)'                                  | ''             | ''          | ''   | ''        
 'BLUE'                     | 'THLF'    | 'L-710A8EW/1QBD-C'          | 'EMPTY'  | 'BEBL0150D00'(!)  = 'End of Design' | 'Comp-Approve' | 'BEBL0150D00'     |'LED_710A8EW'| 'IO'  | 'LED DIP 2P BLUE (L-710A8EW/1QBD-C)'                                  | ''             | ''          | ''   | ''        
 'LED YELLOW'               | 'SMLF'    | '15-21VYC/TR8(HT)     '     | 'IC'     | 'BEYL0008Z05'(!)  = 'End of Design' | 'End of Life'  | 'BEYL0008Z05'     |'LED_1521_ERROR_EOL'| 'IC'  | 'LED(2P,SMD) YELLOW 15-21VYC/TR8(HT)-Need new spec check-20170503   ' | ''             | ''          | ''   | '20100709'
 'LED YELLOW'               | 'SMLF'    | '15-21VYC/TR8(HT)     '     | 'EMPTY'  | 'BEYL0008Z05'(!)  = 'End of Design' | 'End of Life'  | 'BEYL0008Z05'     |'LED_1521_ERROR_EOL'| 'IO'  | 'LED(2P,SMD) YELLOW 15-21VYC/TR8(HT)-Need new spec check-20170503   ' | ''             | ''          | ''   | '20100709'
 'LED AMBER '               | 'SMLF'    | '19-21UYOC-S530-A3-TR8'     | 'IC'     | 'BEAB0014Z00'(!)  = 'End of Design' | 'Comp-Approve' | 'BEAB0014Z00'     |'LED_1921XA'| 'IC'  | 'LED SMD(2P)AMBER(19-21UYOC/S530-A3-TR8)'                             | ''             | ''          | ''   | '20100709'
 'LED AMBER '               | 'SMLF'    | '19-21UYOC-S530-A3-TR8'     | 'EMPTY'  | 'BEAB0014Z00'(!)  = 'End of Design' | 'Comp-Approve' | 'BEAB0014Z00'     |'LED_1921XA'| 'IO'  | 'LED SMD(2P)AMBER(19-21UYOC/S530-A3-TR8)'                             | ''             | ''          | ''   | '20100709'
 'LED RED   '               | 'SMLF'    | '19-21SURC-S530-A3-TR8'     | 'IC'     | 'BERD0035Z03'(!)  = 'End of Design' | 'Comp-Approve' | 'BERD0035Z03'     |'LED_1921XA'| 'IC'  | 'LED SMD(2P) RED(19-21SURC-S530-A3-TR8)'                              | ''             | ''          | ''   | '20100709'
 'LED RED   '               | 'SMLF'    | '19-21SURC-S530-A3-TR8'     | 'EMPTY'  | 'BERD0035Z03'(!)  = 'End of Design' | 'Comp-Approve' | 'BERD0035Z03'     |'LED_1921XA'| 'IO'  | 'LED SMD(2P) RED(19-21SURC-S530-A3-TR8)'                              | ''             | ''          | ''   | '20100709'
 'LED GREEN '               | 'SMLF'    | 'APT2012QGW-F01-INT   '     | 'IC'     | 'BEGR0102Z19'(!)  = 'End of Design' | 'Comp-Approve' | 'BEGR0102Z19'     |'LED_APT2012'| 'IC'  | 'LED SMD(2P)GREEN APT2012QGW-F01-INT   '                              | ''             | ''          | ''   | '20100709'
 'LED GREEN '               | 'SMLF'    | 'APT2012QGW-F01-INT   '     | 'EMPTY'  | 'BEGR0102Z19'(!)  = 'End of Design' | 'Comp-Approve' | 'BEGR0102Z19'     |'LED_APT2012'| 'IO'  | 'LED SMD(2P)GREEN APT2012QGW-F01-INT   '                              | ''             | ''          | ''   | '20100709'
 'LED GREEN '               | 'SMLF'    | 'APT2012NW-F01-INT '        | 'IC'     | 'BE0R0012Z17'(!)  = 'End of Design' | 'Comp-Approve' | 'BE0R0012Z17'     |'LED_APT2012'| 'IC'  | 'LED SMD(2P)ORANGE APT2012NW-F01-INT'                                 | ''             | ''          | ''   | '20100709'
 'LED GREEN '               | 'SMLF'    | 'APT2012NW-F01-INT '        | 'EMPTY'  | 'BE0R0012Z17'(!)  = 'End of Design' | 'Comp-Approve' | 'BE0R0012Z17'     |'LED_APT2012'| 'IO'  | 'LED SMD(2P)ORANGE APT2012NW-F01-INT'                                 | ''             | ''          | ''   | '20100709'
 'LED BLUE'                 | 'THLF'    | 'L-7104EW-1PBD-A-DTS'       | 'IC'     | 'BEBL0141D00'(!)  = 'End of Design' | 'Comp-Approve' | 'BEBL0141D00'     |'LED_710A8EW'| 'IC'  | 'LED DIP(2P) BLUE L-7104EW-1PBD-A-DTS'                                | ''             | ''          | ''   | '20100915'
 'LED BLUE'                 | 'THLF'    | 'L-7104EW-1PBD-A-DTS'       | 'EMPTY'  | 'BEBL0141D00'(!)  = 'End of Design' | 'Comp-Approve' | 'BEBL0141D00'     |'LED_710A8EW'| 'IO'  | 'LED DIP(2P) BLUE L-7104EW-1PBD-A-DTS'                                | ''             | ''          | ''   | '20100915'
 'LED_GREEN'                | 'THLF'    | 'L-7104EW/1GD'              | 'IC'     | 'BEGR0234D00'(!)  = 'End of Design' | 'Comp-Approve' | 'BEGR0234D00'     |'LED_710A8EW'| 'IC'  | 'LED DIP(2P) GREEN L-7104EW/1GD'                                      | ''             | ''          | ''   | '20100915'
 'LED_GREEN'                | 'THLF'    | 'L-7104EW/1GD'              | 'EMPTY'  | 'BEGR0234D00'(!)  = 'End of Design' | 'Comp-Approve' | 'BEGR0234D00'     |'LED_710A8EW'| 'IO'  | 'LED DIP(2P) GREEN L-7104EW/1GD'                                      | ''             | ''          | ''   | '20100915'
 'LED_YELLOW'               | 'SMLF'    | '19-213/Y2C-AP1Q1BZ/3T'     | 'IC'     | 'BEYL0107Z00'(!)  = ''              | ''             | 'BEYL0107Z00'     |'LED_1921'| 'IC'  | 'LED SMD YELLOW (19-213/Y2C-AP1Q1BZ/3T)'                              | ''             | ''          | ''   | '20101125'
 'LED_YELLOW'               | 'SMLF'    | '19-213/Y2C-AP1Q1BZ/3T'     | 'EMPTY'  | 'BEYL0107Z00'(!)  = ''              | ''             | 'BEYL0107Z00'     |'LED_1921'| 'IO'  | 'LED SMD YELLOW (19-213/Y2C-AP1Q1BZ/3T)'                              | ''             | ''          | ''   | '20101125'
 'LED_GREEN'                | 'SMLF'    | 'LTST-C171GKT-T'            | 'IC'     | 'BEGR0182Z00'(!)  = ''              | ''             | 'BEGR0182Z00'     |'LED_C171GKT'| 'IC'  | 'LED SMD(2P) GREEN(LTST-C171GKT-T)'                                   | ''             | ''          | ''   | '20110223'
 'LED_GREEN'                | 'SMLF'    | 'LTST-C171GKT-T'            | 'EMPTY'  | 'BEGR0182Z00'(!)  = ''              | ''             | 'BEGR0182Z00'     |'LED_C171GKT'| 'IO'  | 'LED SMD(2P) GREEN(LTST-C171GKT-T)'                                   | ''             | ''          | ''   | '20110223'
 'LED_ORANGE'               | 'SMLF'    | 'LTST-C170AKT'              | 'IC'     | 'BE0R0008Z01'(!)  = ''              | ''             | 'BE0R0008Z01'     |'LED_170VY_H44'| 'IC'  | 'LED SMD 2P ORANGE (LTST-C170AKT)'                                    | ''             | ''          | ''   | '20110609'
 'LED_ORANGE'               | 'SMLF'    | 'LTST-C170AKT'              | 'EMPTY'  | 'BE0R0008Z01'(!)  = ''              | ''             | 'BE0R0008Z01'     |'LED_170VY_H44'| 'IO'  | 'LED SMD 2P ORANGE (LTST-C170AKT)'                                    | ''             | ''          | ''   | '20110609'
 'LED YELLOW'               | 'SMLF'    | 'LTST-C190KSKT'             | 'IC'     | 'BEYL0024Z01'(!)  = ''              | ''             | 'BEYL0024Z01'     |'LED_1921XA'| 'IC'  | 'LED SMD (2P) YELLOW(LTST-C190KSKT) 0603'                             | ''             | ''          | ''   | '20111207'
 'LED YELLOW'               | 'SMLF'    | 'LTST-C190KSKT'             | 'EMPTY'  | 'BEYL0024Z01'(!)  = ''              | ''             | 'BEYL0024Z01'     |'LED_1921XA'| 'IO'  | 'LED SMD (2P) YELLOW(LTST-C190KSKT) 0603'                             | ''             | ''          | ''   | '20111207'
 'LED SMD BLUE'             | 'SMLF'    | '11-21/BHC-AP1Q2B2Z/2T'     | 'IC'     | 'BEBL0105Z00'(!)  = ''              | ''             | 'BEBL0105Z00'     |'LED_1121'| 'IC'  | 'LED SMD BLUE(11-21/BHC-AP1Q2B2Z/2T)'                                 | ''             | ''          | ''   | '20111207'
 'LED SMD BLUE'             | 'SMLF'    | '11-21/BHC-AP1Q2B2Z/2T'     | 'EMPTY'  | 'BEBL0105Z00'(!)  = ''              | ''             | 'BEBL0105Z00'     |'LED_1121'| 'IO'  | 'LED SMD BLUE(11-21/BHC-AP1Q2B2Z/2T)'                                 | ''             | ''          | ''   | '20111207'
 'LED  GREEN'               | 'SMLF'    | '15-21/GHC-YR1S1/2T'        | 'IC'     | 'BEGR0191Z00'(!)  = ''              | ''             | 'BEGR0191Z00'     |'LED2S_15-21Y2C-AP1Q2B2T'| 'IC'  | 'LED SMD(2P) GREEN(15-21/GHC-YR1S1/2T)'                               | ''             | ''          | ''   | '20170503'
 'LED  GREEN'               | 'SMLF'    | '15-21/GHC-YR1S1/2T'        | 'EMPTY'  | 'BEGR0191Z00'(!)  = ''              | ''             | 'BEGR0191Z00'     |'LED2S_15-21Y2C-AP1Q2B2T'| 'IO'  | 'LED SMD(2P) GREEN(15-21/GHC-YR1S1/2T)'                               | ''             | ''          | ''   | '20170503'
 'LED BLUE'                 | 'SMLF'    | '15-21/BHC-AN1P2/2T'        | 'IC'     | 'BEBL0079Z00'(!)  = ''              | ''             | 'BEBL0079Z00'     |'LED2S_15-21Y2C-AP1Q2B2T'| 'IC'  | 'LED SMD(2P) BLUE 15-21/BHC-AN1P2/2T'                                 | ''             | ''          | ''   | '20170503'
 'LED BLUE'                 | 'SMLF'    | '15-21/BHC-AN1P2/2T'        | 'EMPTY'  | 'BEBL0079Z00'(!)  = ''              | ''             | 'BEBL0079Z00'     |'LED2S_15-21Y2C-AP1Q2B2T'| 'IO'  | 'LED SMD(2P) BLUE 15-21/BHC-AN1P2/2T'                                 | ''             | ''          | ''   | '20170503'
 'LED_YELLOW'               | 'SMLF'    | '15-21/Y2C-AP1Q2B/2T'       | 'IC'     | 'BEYL0089Z00'(!)  = ''              | ''             | 'BEYL0089Z00'     |'LED2S_15-21Y2C-AP1Q2B2T'| 'IC'  | 'LED SMD(2P)YELLOW_15-21/Y2C-AP1Q2B/2T'                               | ''             | ''          | ''   | '20170503'
 'LED_YELLOW'               | 'SMLF'    | '15-21/Y2C-AP1Q2B/2T'       | 'EMPTY'  | 'BEYL0089Z00'(!)  = ''              | ''             | 'BEYL0089Z00'     |'LED2S_15-21Y2C-AP1Q2B2T'| 'IO'  | 'LED SMD(2P)YELLOW_15-21/Y2C-AP1Q2B/2T'                               | ''             | ''          | ''   | '20170503'
 'LED RED'                  | 'THLF'    | 'L-7104EW/1ID'              | 'IC'     | 'BERD0101D00'(!)  = 'End of Design' | 'P/N Release'  | 'BERD0101D00'     |'LED_710A8EW'| 'IC'  | 'LED DIP(2P) RED(L-7104EW/1ID)'                                       | ''             | ''          | ''   | '20120423'
 'LED RED'                  | 'THLF'    | 'L-7104EW/1ID'              | 'EMPTY'  | 'BERD0101D00'(!)  = 'End of Design' | 'P/N Release'  | 'BERD0101D00'     |'LED_710A8EW'| 'IO'  | 'LED DIP(2P) RED(L-7104EW/1ID)'                                       | ''             | ''          | ''   | '20120423'
 'LED GREEN'                | 'THLF'    | 'L-1384AD/1GD-3'            | 'IC'     | 'BEGR0070D00'(!)  = 'End of Design' | 'End of Life'  | 'BEGR0070D00'     |'LED_L1384AD_EOL'| 'IC'  | 'LED DIP(2P) GREEN L-1384AD/1GD-3'                                    | ''             | ''          | ''   | '20121127'
 'LED GREEN'                | 'THLF'    | 'L-1384AD/1GD-3'            | 'EMPTY'  | 'BEGR0070D00'(!)  = 'End of Design' | 'End of Life'  | 'BEGR0070D00'     |'LED_L1384AD_EOL'| 'IO'  | 'LED DIP(2P) GREEN L-1384AD/1GD-3'                                    | ''             | ''          | ''   | '20121127'
 'LED PURE ORANGE'          | 'THLF'    | 'L-1384AD/1ND'              | 'IC'     | 'BE0R0038D01'(!)  = 'End of Design' | 'End of Life'  | 'BE0R0038D01'     |'LED_L1384AD_EOL'| 'IC'  | 'LED DIP(2PIN) PURE ORANGE L-1384AD/1ND'                              | ''             | ''          | ''   | '20121127'
 'LED PURE ORANGE'          | 'THLF'    | 'L-1384AD/1ND'              | 'EMPTY'  | 'BE0R0038D01'(!)  = 'End of Design' | 'End of Life'  | 'BE0R0038D01'     |'LED_L1384AD_EOL'| 'IO'  | 'LED DIP(2PIN) PURE ORANGE L-1384AD/1ND'                              | ''             | ''          | ''   | '20121127'
 'LED ORANGE'               | 'SMLF'    | 'APDA3020-CN24A'            | 'IC'     | 'BE0R0074Z00'(!)  = 'End of Design' | 'Comp-Approve' | 'BE0R0074Z00'     |'LED2S_APDA3020'| 'IC'  | 'LED SMD(4P) ORANGE(APDA3020-CN24A)'                                  | ''             | ''          | ''   | '20121201'
 'LED ORANGE'               | 'SMLF'    | 'APDA3020-CN24A'            | 'EMPTY'  | 'BE0R0074Z00'(!)  = 'End of Design' | 'Comp-Approve' | 'BE0R0074Z00'     |'LED2S_APDA3020'| 'IO'  | 'LED SMD(4P) ORANGE(APDA3020-CN24A)'                                  | ''             | ''          | ''   | '20121201'
 'LED GREEN'                | 'SMLF'    | 'APDA3020-CN26A'            | 'IC'     | 'BEGR0216Z00'(!)  = 'End of Design' | 'Comp-Approve' | 'BEGR0216Z00'     |'LED2S_APDA3020'| 'IC'  | 'LED SMD(4P) GREEN(APDA3020-CN26A)'                                   | ''             | ''          | ''   | '20121201'
 'LED GREEN'                | 'SMLF'    | 'APDA3020-CN26A'            | 'EMPTY'  | 'BEGR0216Z00'(!)  = 'End of Design' | 'Comp-Approve' | 'BEGR0216Z00'     |'LED2S_APDA3020'| 'IO'  | 'LED SMD(4P) GREEN(APDA3020-CN26A)'                                   | ''             | ''          | ''   | '20121201'
 'LED GREEN'                | 'SMLF'    | '15-21VGC/TR8(HT)'          | 'IC'     | 'BEGR0034Z13'(!)  = ''              | 'End of Life'  | 'BEGR0034Z13'     |'LED_1521_ERROR_EOL'| 'IC'  | 'LED(2P.SMD) GREEN 15-21VGC/TR8(HT)-Need new spec check-20170503'     | ''             | ''          | ''   | '20130205'
 'LED GREEN'                | 'SMLF'    | '15-21VGC/TR8(HT)'          | 'EMPTY'  | 'BEGR0034Z13'(!)  = ''              | 'End of Life'  | 'BEGR0034Z13'     |'LED_1521_ERROR_EOL'| 'IO'  | 'LED(2P.SMD) GREEN 15-21VGC/TR8(HT)-Need new spec check-20170503'     | ''             | ''          | ''   | '20130205'
 'LED GREEN'                | 'SMLF'    | '17-21/GHC-YR1S2/3T'        | 'IC'     | 'BEGR0190Z00'(!)  = ''              | ''             | 'BEGR0190Z00'     |'LED_1721'| 'IC'  | 'LED SMD(2P) GREEN(17-21/GHC-YR1S2/3T)'                               | ''             | ''          | ''   | '20130311'
 'LED GREEN'                | 'SMLF'    | '17-21/GHC-YR1S2/3T'        | 'EMPTY'  | 'BEGR0190Z00'(!)  = ''              | ''             | 'BEGR0190Z00'     |'LED_1721'| 'IO'  | 'LED SMD(2P) GREEN(17-21/GHC-YR1S2/3T)'                               | ''             | ''          | ''   | '20130311'
 'LED_BLUE'                 | 'SMLF'    | 'LTST-S270TBKT'             | 'IC'     | 'BEBL0050Z08'(!)  = ''              | ''             | 'BEBL0050Z08'     |'LED_LTSTS270TBKT'| 'IC'  | 'LED SMD (2P) BLUE (LTST-S270TBKT)'                                   | ''             | ''          | ''   | '20130319'
 'LED_BLUE'                 | 'SMLF'    | 'LTST-S270TBKT'             | 'EMPTY'  | 'BEBL0050Z08'(!)  = ''              | ''             | 'BEBL0050Z08'     |'LED_LTSTS270TBKT'| 'IO'  | 'LED SMD (2P) BLUE (LTST-S270TBKT)'                                   | ''             | ''          | ''   | '20130319'
 'LED GREEN'                | 'SMLF'    | '19-213/GHC-YR2U1/3T'       | 'IC'     | 'BEGR0320Z00'(!)  = ''              | ''             | 'BEGR0320Z00'     |'LED_1921'| 'IC'  | 'LED SMD(2P) GREEN 19-213/GHC-YR2U1/3T'                               | ''             | ''          | ''   | '20130503'
 'LED GREEN'                | 'SMLF'    | '19-213/GHC-YR2U1/3T'       | 'EMPTY'  | 'BEGR0320Z00'(!)  = ''              | ''             | 'BEGR0320Z00'     |'LED_1921'| 'IO'  | 'LED SMD(2P) GREEN 19-213/GHC-YR2U1/3T'                               | ''             | ''          | ''   | '20130503'
 'LED_SMD_YELLOW'           | 'SMLF'    | '19-213/Y2C-AP1Q1BZ/3T'     | 'IC'     | 'BEYL0107Z00'(!)  = ''              | ''             | 'BEYL0107Z00'     |'LED_1921'| 'IC'  | 'LED SMD YELLOW (19-213/Y2C-AP1Q1BZ/3T)'                              | ''             | ''          | ''   | '20130503'
 'LED_SMD_YELLOW'           | 'SMLF'    | '19-213/Y2C-AP1Q1BZ/3T'     | 'EMPTY'  | 'BEYL0107Z00'(!)  = ''              | ''             | 'BEYL0107Z00'     |'LED_1921'| 'IO'  | 'LED SMD YELLOW (19-213/Y2C-AP1Q1BZ/3T)'                              | ''             | ''          | ''   | '20130503'
 'LED GREEN'                | 'SMLF'    | 'APT2012-CN26'              | 'IC'     | 'BEGR0266Z00'(!)  = 'End of Design' | 'Comp-Approve' | 'BEGR0266Z00'     |'LED_APT2012'| 'IC'  | 'LED SMD(2P)GREEN APT2012-CN26'                                       | ''             | ''          | ''   | '20130506'
 'LED GREEN'                | 'SMLF'    | 'APT2012-CN26'              | 'EMPTY'  | 'BEGR0266Z00'(!)  = 'End of Design' | 'Comp-Approve' | 'BEGR0266Z00'     |'LED_APT2012'| 'IO'  | 'LED SMD(2P)GREEN APT2012-CN26'                                       | ''             | ''          | ''   | '20130506'
 'LED YELLOW'               | 'SMLF'    | 'KPTD-1608SYCK'             | 'IC'     | 'BEYL0122Z00'(!)  = 'End of Design' | 'P/N Release'  | 'BEYL0122Z00'     |'LED_KPTD-1608'| 'IC'  | 'LED SMD(2P)YELLOW(KPTD-1608SYCK)'                                    | ''             | ''          | ''   | '20130513'
 'LED YELLOW'               | 'SMLF'    | 'KPTD-1608SYCK'             | 'EMPTY'  | 'BEYL0122Z00'(!)  = 'End of Design' | 'P/N Release'  | 'BEYL0122Z00'     |'LED_KPTD-1608'| 'IO'  | 'LED SMD(2P)YELLOW(KPTD-1608SYCK)'                                    | ''             | ''          | ''   | '20130513'
 'LED GREEN'                | 'SMLF'    | 'KPTD-1608ZGC'              | 'IC'     | 'BEGR0303Z00'(!)  = 'End of Design' | 'P/N Release'  | 'BEGR0303Z00'     |'LED_KPTD-1608'| 'IC'  | 'LED SMD(2P)GREEN KPTD-1608ZGC'                                       | ''             | ''          | ''   | '20130518'
 'LED GREEN'                | 'SMLF'    | 'KPTD-1608ZGC'              | 'EMPTY'  | 'BEGR0303Z00'(!)  = 'End of Design' | 'P/N Release'  | 'BEGR0303Z00'     |'LED_KPTD-1608'| 'IO'  | 'LED SMD(2P)GREEN KPTD-1608ZGC'                                       | ''             | ''          | ''   | '20130518'
 'LED YEL/GR'               | 'SMLF'    | '19-213SYGC/S313/TR8'       | 'IC'     | 'BEYG0075ZA1'(!)  = ''              | ''             | 'BEYG0075ZA1'     |'LED_1921'| 'IC'  | 'LED SMD(2P)YEL/GR 19-213SYGC/S313/TR8'                               | ''             | ''          | ''   | '20130611'
 'LED YEL/GR'               | 'SMLF'    | '19-213SYGC/S313/TR8'       | 'EMPTY'  | 'BEYG0075ZA1'(!)  = ''              | ''             | 'BEYG0075ZA1'     |'LED_1921'| 'IO'  | 'LED SMD(2P)YEL/GR 19-213SYGC/S313/TR8'                               | ''             | ''          | ''   | '20130611'
 'LED BLUE'                 | 'SMLF'    | '19-217/BHC-YL2M2TY/3T'     | 'IC'     | 'BEBL0031Z11'(!)  = 'End of Design' | 'End of Life'  | 'BEBL0031Z11'     |'LED_19217_EOL'| 'IC'  | 'LED SMD(2P) BLUE 19-217BHCYL2M2TY3T'                                 | ''             | ''          | ''   | '20130611'
 'LED BLUE'                 | 'SMLF'    | '19-217/BHC-YL2M2TY/3T'     | 'EMPTY'  | 'BEBL0031Z11'(!)  = 'End of Design' | 'End of Life'  | 'BEBL0031Z11'     |'LED_19217_EOL'| 'IO'  | 'LED SMD(2P) BLUE 19-217BHCYL2M2TY3T'                                 | ''             | ''          | ''   | '20130611'
 'LED ORANGE'               | 'SMLF'    | '19-213/S2C-AP2Q2B/3T'      | 'IC'     | 'BE0R0104Z00'(!)  = ''              | ''             | 'BE0R0104Z00'     |'LED_1921'| 'IC'  | 'LED SMD ORANGE(19-213/S2C-AP2Q2B/3T)'                                | ''             | ''          | ''   | '20130611'
 'LED ORANGE'               | 'SMLF'    | '19-213/S2C-AP2Q2B/3T'      | 'EMPTY'  | 'BE0R0104Z00'(!)  = ''              | ''             | 'BE0R0104Z00'     |'LED_1921'| 'IO'  | 'LED SMD ORANGE(19-213/S2C-AP2Q2B/3T)'                                | ''             | ''          | ''   | '20130611'
 'LED GREEN'                | 'THLF'    | 'LTL42TG6NH213'             | 'IC'     | 'BEGR0304D00'(!)  = ''              | ''             | 'BEGR0304D00'     |'LED2P_LTL42'| 'IC'  | 'LED(DIP) GREEN(LTL42TG6NH213)'                                       | ''             | ''          | ''   | '20130614'
 'LED GREEN'                | 'THLF'    | 'LTL42TG6NH213'             | 'EMPTY'  | 'BEGR0304D00'(!)  = ''              | ''             | 'BEGR0304D00'     |'LED2P_LTL42'| 'IO'  | 'LED(DIP) GREEN(LTL42TG6NH213)'                                       | ''             | ''          | ''   | '20130614'
 'LED YELLOW'               | 'THLF'    | 'LTL42NKSDH213'             | 'IC'     | 'BEYL0123D00'(!)  = ''              | ''             | 'BEYL0123D00'     |'LED2P_LTL42'| 'IC'  | 'LED(DIP)YELLOW(LTL42NKSDH213)'                                       | ''             | ''          | ''   | '20130614'
 'LED YELLOW'               | 'THLF'    | 'LTL42NKSDH213'             | 'EMPTY'  | 'BEYL0123D00'(!)  = ''              | ''             | 'BEYL0123D00'     |'LED2P_LTL42'| 'IO'  | 'LED(DIP)YELLOW(LTL42NKSDH213)'                                       | ''             | ''          | ''   | '20130614'
 'LED_GREEN'                | 'SMLF'    | 'LTST-C190KGKT'             | 'IC'     | 'BEGR0080Z07'(!)  = 'End of Design' | 'Comp-Approve' | 'BEGR0080Z07'     |'LED_1921XA'| 'IC'  | 'LED SMD (2P)GREEN LTST-C190KGKT 0603'                                | ''             | ''          | ''   | '20130925'
 'LED_GREEN'                | 'SMLF'    | 'LTST-C190KGKT'             | 'EMPTY'  | 'BEGR0080Z07'(!)  = 'End of Design' | 'Comp-Approve' | 'BEGR0080Z07'     |'LED_1921XA'| 'IO'  | 'LED SMD (2P)GREEN LTST-C190KGKT 0603'                                | ''             | ''          | ''   | '20130925'
 'LED_GREEN'                | 'SMLF'    | 'LTST-C281KGKT-5A'          | 'IC'     | 'BEGR0300Z00'(!)  = ''              | ''             | 'BEGR0300Z00'     |'LED2S_0402'| 'IC'  | 'LED SMD(2P) GREEN(LTST-C281KGKT-5A)'                                 | ''             | ''          | ''   | '20140109'
 'LED_GREEN'                | 'SMLF'    | 'LTST-C281KGKT-5A'          | 'EMPTY'  | 'BEGR0300Z00'(!)  = ''              | ''             | 'BEGR0300Z00'     |'LED2S_0402'| 'IO'  | 'LED SMD(2P) GREEN(LTST-C281KGKT-5A)'                                 | ''             | ''          | ''   | '20140109'
 'LED_BLUE'                 | 'THLF'    | 'A214B/SUBC/S400-A6/F14-33' | 'IC'     | 'BEBL0221D00'(!)  = ''              | ''             | 'BEBL0221D00'     |'LED2P_A214BSUBCS400-A6F14-33'| 'IC'  | 'LED DIP(2P)BL A214B/SUBC/S400-A6/F14-33'                             | ''             | ''          | ''   | '20140715'
 'LED_BLUE'                 | 'THLF'    | 'A214B/SUBC/S400-A6/F14-33' | 'EMPTY'  | 'BEBL0221D00'(!)  = ''              | ''             | 'BEBL0221D00'     |'LED2P_A214BSUBCS400-A6F14-33'| 'IO'  | 'LED DIP(2P)BL A214B/SUBC/S400-A6/F14-33'                             | ''             | ''          | ''   | '20140715'
 'LED_BLUE'                 | 'SMLF'    | '19-117/BHC-YL2M2QY/3T'     | 'IC'     | 'BEBL0148Z00'(!)  = ''              | ''             | 'BEBL0148Z00'     |'LED_1921'| 'IC'  | 'LED SMD(2P) BLUE 19-117/BHC-YL2M2QY/3T'                              | ''             | ''          | ''   | '20140729'
 'LED_BLUE'                 | 'SMLF'    | '19-117/BHC-YL2M2QY/3T'     | 'EMPTY'  | 'BEBL0148Z00'(!)  = ''              | ''             | 'BEBL0148Z00'     |'LED_1921'| 'IO'  | 'LED SMD(2P) BLUE 19-117/BHC-YL2M2QY/3T'                              | ''             | ''          | ''   | '20140729'
 'LED_RED'                  | 'SMLF'    | '19-21SDRC/S530-A2/TR8'     | 'IC'     | 'BERD0115Z00'(!)  = ''              | ''             | 'BERD0115Z00'     |'LED_1921XA'| 'IC'  | 'LED SMD(2P) RED 19-21SDRC/S530-A2/TR8'                               | ''             | ''          | ''   | '20140811'
 'LED_RED'                  | 'SMLF'    | '19-21SDRC/S530-A2/TR8'     | 'EMPTY'  | 'BERD0115Z00'(!)  = ''              | ''             | 'BERD0115Z00'     |'LED_1921XA'| 'IO'  | 'LED SMD(2P) RED 19-21SDRC/S530-A2/TR8'                               | ''             | ''          | ''   | '20140811'
 'LED_WHITE'                | 'SMLF'    | 'LTW-S272TLA'               | 'IC'     | 'BEWH0175Z00'(!)  = ''              | ''             | 'BEWH0175Z00'     |'LED2S_LTW-S272TLA'| 'IC'  | 'LED SMD(2P) WHITE(LTW-S272TLA)'                                      | ''             | ''          | ''   | '20140811'
 'LED_WHITE'                | 'SMLF'    | 'LTW-S272TLA'               | 'EMPTY'  | 'BEWH0175Z00'(!)  = ''              | ''             | 'BEWH0175Z00'     |'LED2S_LTW-S272TLA'| 'IO'  | 'LED SMD(2P) WHITE(LTW-S272TLA)'                                      | ''             | ''          | ''   | '20140811'
 'LED_GREEN'                | 'SMLF'    | 'LTST-C171KGKT'             | 'IC'     | 'BEGR0248Z00'(!)  = ''              | ''             | 'BEGR0248Z00'     |'LED_C171GKT'| 'IC'  | 'LED SMD 2P GREEN(LTST-C171KGKT)'                                     | ''             | ''          | ''   | '20140818'
 'LED_GREEN'                | 'SMLF'    | 'LTST-C171KGKT'             | 'EMPTY'  | 'BEGR0248Z00'(!)  = ''              | ''             | 'BEGR0248Z00'     |'LED_C171GKT'| 'IO'  | 'LED SMD 2P GREEN(LTST-C171KGKT)'                                     | ''             | ''          | ''   | '20140818'
 'LED_YELLOW'               | 'SMLF'    | '27-21UYC/S530-A3/TR8'      | 'IC'     | 'BEYL0038Z01'(!)  = ''              | ''             | 'BEYL0038Z01'     |'LED2S_27-21UYC'| 'IC'  | 'LED SMD(2P)YELLOW(27-21UYC/S530-A3/TR8)'                             | ''             | ''          | ''   | '20140821'
 'LED_YELLOW'               | 'SMLF'    | '27-21UYC/S530-A3/TR8'      | 'EMPTY'  | 'BEYL0038Z01'(!)  = ''              | ''             | 'BEYL0038Z01'     |'LED2S_27-21UYC'| 'IO'  | 'LED SMD(2P)YELLOW(27-21UYC/S530-A3/TR8)'                             | ''             | ''          | ''   | '20140821'
 'LED_GREEN'                | 'SMLF'    | 'LTST-C190KGKT-Q'           | 'IC'     | 'BEGR0100Z08'(!)  = ''              | ''             | 'BEGR0100Z08'     |'LED_1921XA'| 'IC'  | 'LED SMD(2P)GREEN LTST-C190KGKT-Q 0603'                               | ''             | ''          | ''   | '20140901'
 'LED_GREEN'                | 'SMLF'    | 'LTST-C190KGKT-Q'           | 'EMPTY'  | 'BEGR0100Z08'(!)  = ''              | ''             | 'BEGR0100Z08'     |'LED_1921XA'| 'IO'  | 'LED SMD(2P)GREEN LTST-C190KGKT-Q 0603'                               | ''             | ''          | ''   | '20140901'
 'LED_BLUE'                 | 'SMLF'    | 'LTST-C170TBKT'             | 'IC'     | 'BEBL0049Z00'(!)  = ''              | ''             | 'BEBL0049Z00'     |'LED_170VY_H44'| 'IC'  | 'LED SMD 2P BLUE(LTST-C170TBKT)'                                      | ''             | ''          | ''   | '20140903'
 'LED_BLUE'                 | 'SMLF'    | 'LTST-C170TBKT'             | 'EMPTY'  | 'BEBL0049Z00'(!)  = ''              | ''             | 'BEBL0049Z00'     |'LED_170VY_H44'| 'IO'  | 'LED SMD 2P BLUE(LTST-C170TBKT)'                                      | ''             | ''          | ''   | '20140903'
 'LED_RED'                  | 'SMLF'    | 'LTST-C190KRKT'             | 'IC'     | 'BERD0021Z02'(!)  = ''              | ''             | 'BERD0021Z02'     |'LED_1921XA'| 'IC'  | 'LED SMD (2P) RED(LTST-C190KRKT) 0603'                                | ''             | ''          | ''   | '20141020'
 'LED_RED'                  | 'SMLF'    | 'LTST-C190KRKT'             | 'EMPTY'  | 'BERD0021Z02'(!)  = ''              | ''             | 'BERD0021Z02'     |'LED_1921XA'| 'IO'  | 'LED SMD (2P) RED(LTST-C190KRKT) 0603'                                | ''             | ''          | ''   | '20141020'
 'LED_ORANGE'               | 'SMLF'    | 'LTST-C190AKT'              | 'IC'     | 'BE0R0096Z00'(!)  = ''              | ''             | 'BE0R0096Z00'     |'LED_1921XA'| 'IC'  | 'LED SMD(2P) ORANGE (LTST-C190AKT)'                                   | ''             | ''          | ''   | '20141023'
 'LED_ORANGE'               | 'SMLF'    | 'LTST-C190AKT'              | 'EMPTY'  | 'BE0R0096Z00'(!)  = ''              | ''             | 'BE0R0096Z00'     |'LED_1921XA'| 'IO'  | 'LED SMD(2P) ORANGE (LTST-C190AKT)'                                   | ''             | ''          | ''   | '20141023'
 'LED_WHITE'                | 'SMLF'    | 'LTW-C191UC5'               | 'IC'     | 'BEWH0047Z00'(!)  = ''              | ''             | 'BEWH0047Z00'     |'LED_19217_H22'| 'IC'  | 'LED SMD 2P WHITE(LTW-C191UC5)'                                       | ''             | ''          | ''   | '20150203'
 'LED_WHITE'                | 'SMLF'    | 'LTW-C191UC5'               | 'EMPTY'  | 'BEWH0047Z00'(!)  = ''              | ''             | 'BEWH0047Z00'     |'LED_19217_H22'| 'IO'  | 'LED SMD 2P WHITE(LTW-C191UC5)'                                       | ''             | ''          | ''   | '20150203'
 'LED_BLUE'                 | 'SMLF'    | 'LTST-C190TBKT'             | 'IC'     | 'BEBL0019Z03'(!)  = ''              | ''             | 'BEBL0019Z03'     |'LED_1921'| 'IC'  | 'LED SMD (2P) BLUE(LTST-C190TBKT)0603'                                | ''             | ''          | ''   | '20150203'
 'LED_BLUE'                 | 'SMLF'    | 'LTST-C190TBKT'             | 'EMPTY'  | 'BEBL0019Z03'(!)  = ''              | ''             | 'BEBL0019Z03'     |'LED_1921'| 'IO'  | 'LED SMD (2P) BLUE(LTST-C190TBKT)0603'                                | ''             | ''          | ''   | '20150203'
 'LED_BLUE'                 | 'SMLF'    | '19-217/BHC-ZM1N2TY/3T'     | 'IC'     | 'BEBL0224Z00'(!)  = ''              | ''             | 'BEBL0224Z00'     |'LED_19217'| 'IC'  | 'LED SMD(2P) BLUE 19-217/BHC-ZM1N2TY/3T'                              | ''             | ''          | ''   | '20150203'
 'LED_BLUE'                 | 'SMLF'    | '19-217/BHC-ZM1N2TY/3T'     | 'EMPTY'  | 'BEBL0224Z00'(!)  = ''              | ''             | 'BEBL0224Z00'     |'LED_19217'| 'IO'  | 'LED SMD(2P) BLUE 19-217/BHC-ZM1N2TY/3T'                              | ''             | ''          | ''   | '20150203'
 'LED_RED'                  | 'SMLF'    | '19-217/R6C-P1Q2/3T'        | 'IC'     | 'BERD0034Z07'(!)  = ''              | ''             | 'BERD0034Z07'     |'LED_19217'| 'IC'  | 'LED SMD(2P) RED (19-217/R6C-P1Q2/3T)'                                | ''             | ''          | ''   | '20150203'
 'LED_RED'                  | 'SMLF'    | '19-217/R6C-P1Q2/3T'        | 'EMPTY'  | 'BERD0034Z07'(!)  = ''              | ''             | 'BERD0034Z07'     |'LED_19217'| 'IO'  | 'LED SMD(2P) RED (19-217/R6C-P1Q2/3T)'                                | ''             | ''          | ''   | '20150203'
 'LED_WHITE'                | 'SMLF'    | '19-117/T1D-AP2Q2QY/3T'     | 'IC'     | 'BEWH0160Z01'(!)  = ''              | ''             | 'BEWH0160Z01'     |'LED_19217'| 'IC'  | 'LED SMD(2P) WHITE(19-117/T1D-AP2Q2QY/3T)'                            | ''             | ''          | ''   | '20150203'
 'LED_WHITE'                | 'SMLF'    | '19-117/T1D-AP2Q2QY/3T'     | 'EMPTY'  | 'BEWH0160Z01'(!)  = ''              | ''             | 'BEWH0160Z01'     |'LED_19217'| 'IO'  | 'LED SMD(2P) WHITE(19-117/T1D-AP2Q2QY/3T)'                            | ''             | ''          | ''   | '20150203'
 'LED_RED'                  | 'SMLF'    | 'LTST-C193KRKT-SR'          | 'IC'     | 'BERD0090Z00'(!)  = ''              | ''             | 'BERD0090Z00'     |'LED_19217'| 'IC'  | 'LED SMD(2P) RED(LTST-C193KRKT-SR)'                                   | ''             | ''          | ''   | '20150303'
 'LED_RED'                  | 'SMLF'    | 'LTST-C193KRKT-SR'          | 'EMPTY'  | 'BERD0090Z00'(!)  = ''              | ''             | 'BERD0090Z00'     |'LED_19217'| 'IO'  | 'LED SMD(2P) RED(LTST-C193KRKT-SR)'                                   | ''             | ''          | ''   | '20150303'
 'LED_GREEN'                | 'SMLF'    | '19-213/GVC-AMNB/3T'        | 'IC'     | 'BEGR0278Z00'(!)  = ''              | ''             | 'BEGR0278Z00'     |'LED_1921'| 'IC'  | 'LED SMD(2P) GREEN(19-213/GVC-AMNB/3T)'                               | ''             | ''          | ''   | '20150305'
 'LED_GREEN'                | 'SMLF'    | '19-213/GVC-AMNB/3T'        | 'EMPTY'  | 'BEGR0278Z00'(!)  = ''              | ''             | 'BEGR0278Z00'     |'LED_1921'| 'IO'  | 'LED SMD(2P) GREEN(19-213/GVC-AMNB/3T)'                               | ''             | ''          | ''   | '20150305'
 'LED_WHITE'                | 'SMLF'    | 'LTW-270TLA'                | 'IC'     | 'BEWH0043Z00'(!)  = ''              | ''             | 'BEWH0043Z00'     |'LED_LTSTS270TBKT'| 'IC'  | 'LED SMD(2P) WHITE(LTW-270TLA)0603'                                   | ''             | ''          | ''   | '20150414'
 'LED_WHITE'                | 'SMLF'    | 'LTW-270TLA'                | 'EMPTY'  | 'BEWH0043Z00'(!)  = ''              | ''             | 'BEWH0043Z00'     |'LED_LTSTS270TBKT'| 'IO'  | 'LED SMD(2P) WHITE(LTW-270TLA)0603'                                   | ''             | ''          | ''   | '20150414'
 'LED_RED'                  | 'SMLF'    | '17-215SDRC/S530-A2/TR8'    | 'IC'     | 'BERD0044Z00'(!)  = ''              | ''             | 'BERD0044Z00'     |'LED2S_17-215SDRC'| 'IC'  | 'LED SMD(2P) RED(17-215SDRC/S530-A2/TR8)'                             | ''             | ''          | ''   | '20150811'
 'LED_RED'                  | 'SMLF'    | '17-215SDRC/S530-A2/TR8'    | 'EMPTY'  | 'BERD0044Z00'(!)  = ''              | ''             | 'BERD0044Z00'     |'LED2S_17-215SDRC'| 'IO'  | 'LED SMD(2P) RED(17-215SDRC/S530-A2/TR8)'                             | ''             | ''          | ''   | '20150811'
 'LED_GREEN'                | 'SMLF'    | '17-215/GVC-ALMB/3T'        | 'IC'     | 'BEGR0157Z00'(!)  = ''              | ''             | 'BEGR0157Z00'     |'LED2S_17-215SDRC'| 'IC'  | 'LED SMD(2P)GREEN 17-215/GVC-ALMB/3T'                                 | ''             | ''          | ''   | '20150811'
 'LED_GREEN'                | 'SMLF'    | '17-215/GVC-ALMB/3T'        | 'EMPTY'  | 'BEGR0157Z00'(!)  = ''              | ''             | 'BEGR0157Z00'     |'LED2S_17-215SDRC'| 'IO'  | 'LED SMD(2P)GREEN 17-215/GVC-ALMB/3T'                                 | ''             | ''          | ''   | '20150811'
 'LED_BLUE'                 | 'SMLF'    | '17-21/BHC-AK1L2TX/3T'      | 'IC'     | 'BEBL0218Z00'(!)  = ''              | ''             | 'BEBL0218Z00'     |'LED_1721'| 'IC'  | 'LED SMD(2P) BLUE(17-21/BHC-AK1L2TX/3T)'                              | ''             | ''          | ''   | '20150811'
 'LED_BLUE'                 | 'SMLF'    | '17-21/BHC-AK1L2TX/3T'      | 'EMPTY'  | 'BEBL0218Z00'(!)  = ''              | ''             | 'BEBL0218Z00'     |'LED_1721'| 'IO'  | 'LED SMD(2P) BLUE(17-21/BHC-AK1L2TX/3T)'                              | ''             | ''          | ''   | '20150811'
 'LED_BLUE'                 | 'SMLF'    | '16-213/BHC-ZM1N2QY/3T'     | 'IC'     | 'BEBL0230Z00'(!)  = ''              | ''             | 'BEBL0230Z00'     |'LED2S_0402XA'| 'IC'  | 'LED SMD(2P)BLUE(16-213/BHC-ZM1N2QY/3T)'                              | ''             | ''          | ''   | '20151026'
 'LED_BLUE'                 | 'SMLF'    | '16-213/BHC-ZM1N2QY/3T'     | 'EMPTY'  | 'BEBL0230Z00'(!)  = ''              | ''             | 'BEBL0230Z00'     |'LED2S_0402XA'| 'IO'  | 'LED SMD(2P)BLUE(16-213/BHC-ZM1N2QY/3T)'                              | ''             | ''          | ''   | '20151026'
 'LED_GREEN'                | 'SMLF'    | 'LTST-C193KGKT-5A'          | 'IC'     | 'BEGR0272Z00'(!)  = ''              | ''             | 'BEGR0272Z00'     |'LED_19217'| 'IC'  | 'LED SMD(2P)GREEN (LTST-C193KGKT-5A)'                                 | ''             | ''          | ''   | '20160119'
 'LED_GREEN'                | 'SMLF'    | 'LTST-C193KGKT-5A'          | 'EMPTY'  | 'BEGR0272Z00'(!)  = ''              | ''             | 'BEGR0272Z00'     |'LED_19217'| 'IO'  | 'LED SMD(2P)GREEN (LTST-C193KGKT-5A)'                                 | ''             | ''          | ''   | '20160119'
 'LED_GREEN'                | 'SMLF'    | 'LTST-C193KGKT-PE'          | 'IC'     | 'BEGR0003Z00'(!)  = ''              | ''             | 'BEGR0003Z00'     |'LED_19217'| 'IC'  | 'LED SMD(2P)GREEN(LTST-C193KGKT-PE)'                                  | ''             | ''          | ''   | '20160202'
 'LED_GREEN'                | 'SMLF'    | 'LTST-C193KGKT-PE'          | 'EMPTY'  | 'BEGR0003Z00'(!)  = ''              | ''             | 'BEGR0003Z00'     |'LED_19217'| 'IO'  | 'LED SMD(2P)GREEN(LTST-C193KGKT-PE)'                                  | ''             | ''          | ''   | '20160202'
 'LED_GREEN'                | 'THLF'    | 'LTL-42NGY8DHBP-1'          | 'IC'     | 'BEGR0001D00'(!)  = ''              | ''             | 'BEGR0001D00'     |'LED2P_LTL-14CDJNHBP'| 'IC'  | 'LED DIP (2P) GREEN (LTL-42NGY8DHBP-1)'                               | ''             | ''          | ''   | '20160218'
 'LED_GREEN'                | 'THLF'    | 'LTL-42NGY8DHBP-1'          | 'EMPTY'  | 'BEGR0001D00'(!)  = ''              | ''             | 'BEGR0001D00'     |'LED2P_LTL-14CDJNHBP'| 'IO'  | 'LED DIP (2P) GREEN (LTL-42NGY8DHBP-1)'                               | ''             | ''          | ''   | '20160218'
 'LED2P_LTL42NKFDH184'      | 'THLF'    | 'LTL42NKFDH184'             | 'IC'     | 'BEAB0000D00'(!)  = ''              | ''             | 'BEAB0000D00'     |'LED2P_LTL42NKFDH184'| 'IC'  | 'LED DIP(2P)AMBER(LTL42NKFDH184)'                                     | ''             | ''          | ''   | '20160628'
 'LED2P_LTL42NKFDH184'      | 'THLF'    | 'LTL42NKFDH184'             | 'EMPTY'  | 'BEAB0000D00'(!)  = ''              | ''             | 'BEAB0000D00'     |'LED2P_LTL42NKFDH184'| 'IO'  | 'LED DIP(2P)AMBER(LTL42NKFDH184)'                                     | ''             | ''          | ''   | '20160628'
 'LED_BLUE'                 | 'THLF'    | 'LTL42TB6NH184'             | 'IC'     | 'BEBL0216D00'(!)  = ''              | ''             | 'BEBL0216D00'     |'LED2P_LTL42TB6NH184'| 'IC'  | 'LED DIP(2P)BLUE(LTL42TB6NH184)'                                      | ''             | ''          | ''   | '20160630'
 'LED_BLUE'                 | 'THLF'    | 'LTL42TB6NH184'             | 'EMPTY'  | 'BEBL0216D00'(!)  = ''              | ''             | 'BEBL0216D00'     |'LED2P_LTL42TB6NH184'| 'IO'  | 'LED DIP(2P)BLUE(LTL42TB6NH184)'                                      | ''             | ''          | ''   | '20160630'
 'LED_BLUE'                 | 'SMLF'    | 'LTST-C930TBKT'             | 'IC'     | 'BEBL0009Z00'(!)  = ''              | ''             | 'BEBL0009Z00'     |'LED2S_LTST-C930TBKT'| 'IC'  | 'LED SMD(2P)BLUE(LTST-C930TBKT)'                                      | ''             | ''          | ''   | '20160620'
 'LED_BLUE'                 | 'SMLF'    | 'LTST-C930TBKT'             | 'EMPTY'  | 'BEBL0009Z00'(!)  = ''              | ''             | 'BEBL0009Z00'     |'LED2S_LTST-C930TBKT'| 'IO'  | 'LED SMD(2P)BLUE(LTST-C930TBKT)'                                      | ''             | ''          | ''   | '20160620'
 'LED_BLUE'                 | 'SMLF'    | '27-21/BHC-ZM2N2TY/3C'      | 'IC'     | 'BEBL0005Z00'(!)  = ''              | ''             | 'BEBL0005Z00'     |'LED2S_27-21BHC-ZM2N2TY3C'| 'IC'  | 'LED SMD(2P)BLUE(27-21/BHC-ZM2N2TY/3C)'                               | ''             | ''          | ''   | '20160810'
 'LED_BLUE'                 | 'SMLF'    | '27-21/BHC-ZM2N2TY/3C'      | 'EMPTY'  | 'BEBL0005Z00'(!)  = ''              | ''             | 'BEBL0005Z00'     |'LED2S_27-21BHC-ZM2N2TY3C'| 'IO'  | 'LED SMD(2P)BLUE(27-21/BHC-ZM2N2TY/3C)'                               | ''             | ''          | ''   | '20160810'
 'LED_RED'                  | 'THLF'    | 'LTL-4221NHBP'              | 'IC'     | 'BERD0002D00'(!)  = ''              | ''             | 'BERD0002D00'     |'LED2P_LTL-14CDJNHBP'| 'IC'  | 'LED DIP(2P)RED(LTL-4221NHBP)'                                        | ''             | ''          | ''   | '20160831'
 'LED_RED'                  | 'THLF'    | 'LTL-4221NHBP'              | 'EMPTY'  | 'BERD0002D00'(!)  = ''              | ''             | 'BERD0002D00'     |'LED2P_LTL-14CDJNHBP'| 'IO'  | 'LED DIP(2P)RED(LTL-4221NHBP)'                                        | ''             | ''          | ''   | '20160831'
 'LED_BLUE'                 | 'THLF'    | 'LTL42TB6NHBP'              | 'IC'     | 'BEBL0042D08'(!)  = ''              | ''             | 'BEBL0042D08'     |'LED2P_LTL42TB6NHBP'| 'IC'  | 'LED DIP BLUE(3 LTL42TB6NHBP)'                                        | ''             | ''          | ''   | '20160912'
 'LED_BLUE'                 | 'THLF'    | 'LTL42TB6NHBP'              | 'EMPTY'  | 'BEBL0042D08'(!)  = ''              | ''             | 'BEBL0042D08'     |'LED2P_LTL42TB6NHBP'| 'IO'  | 'LED DIP BLUE(3 LTL42TB6NHBP)'                                        | ''             | ''          | ''   | '20160912'
 'LED_YELLOW'               | 'SMLF'    | 'LY M67K-J1L2-26'           | 'IC'     | 'BEYL0006Z00'(!)  = ''              | ''             | 'BEYL0006Z00'     |'LED2S_LYM67K-J1L2-26'| 'IC'  | 'LED SMD(2P)YELLOW(LY M67K-J1L2-26)'                                  | ''             | ''          | ''   | '20161014'
 'LED_YELLOW'               | 'SMLF'    | 'LY M67K-J1L2-26'           | 'EMPTY'  | 'BEYL0006Z00'(!)  = ''              | ''             | 'BEYL0006Z00'     |'LED2S_LYM67K-J1L2-26'| 'IO'  | 'LED SMD(2P)YELLOW(LY M67K-J1L2-26)'                                  | ''             | ''          | ''   | '20161014'
 'LED_AMBER'                | 'SMLF'    | 'LTST-C190KFKT'             | 'IC'     | 'BEAB0006Z07'(!)  = ''              | ''             | 'BEAB0006Z07'     |'LED_1921'| 'IC'  | 'LED SMD(2P)AMBER (LTST-C190KFKT) 0603'                               | ''             | ''          | ''   | '20161018'
 'LED_AMBER'                | 'SMLF'    | 'LTST-C190KFKT'             | 'EMPTY'  | 'BEAB0006Z07'(!)  = ''              | ''             | 'BEAB0006Z07'     |'LED_1921'| 'IO'  | 'LED SMD(2P)AMBER (LTST-C190KFKT) 0603'                               | ''             | ''          | ''   | '20161018'
 'LED_ORANGE'               | 'SMLF'    | '19-213/S2C-AQ2R2B/3T'      | 'IC'     | 'BE0R0001Z00'(!)  = ''              | ''             | 'BE0R0001Z00'     |'LED_1921'| 'IC'  | 'LED SMD(2P)ORANGE(19-213/S2C-AQ2R2B/3T)'                             | ''             | ''          | ''   | '20170105'
 'LED_ORANGE'               | 'SMLF'    | '19-213/S2C-AQ2R2B/3T'      | 'EMPTY'  | 'BE0R0001Z00'(!)  = ''              | ''             | 'BE0R0001Z00'     |'LED_1921'| 'IO'  | 'LED SMD(2P)ORANGE(19-213/S2C-AQ2R2B/3T)'                             | ''             | ''          | ''   | '20170105'
 'LED_GREEN'                | 'SMLF'    | 'L-C170JGCT'                | 'IC'     | 'BEGR0006Z00'(!)  = ''              | ''             | 'BEGR0006Z00'     |'LED2S_L-C170JGCT'| 'IC'  | 'LED SMD(2P)GREEN(L-C170JGCT)'                                        | ''             | ''          | ''   | '20170710'
 'LED_GREEN'                | 'SMLF'    | 'L-C170JGCT'                | 'EMPTY'  | 'BEGR0006Z00'(!)  = ''              | ''             | 'BEGR0006Z00'     |'LED2S_L-C170JGCT'| 'IO'  | 'LED SMD(2P)GREEN(L-C170JGCT)'                                        | ''             | ''          | ''   | '20170710'
 'LED BLUE'                 | 'SMLF'    | 'LTST-C191TBKT-DE'          | 'IC'     | 'BEBL0057Z02'(!)  = ''              | ''             | 'BEBL0057Z02'     |'LED_19217_H22'| 'IC'  | 'LED SMD BLUE(LTST-C191TBKT-DE)'                                      | ''             | ''          | ''   | '20170816'
 'LED BLUE'                 | 'SMLF'    | 'LTST-C191TBKT-DE'          | 'EMPTY'  | 'BEBL0057Z02'(!)  = ''              | ''             | 'BEBL0057Z02'     |'LED_19217_H22'| 'IO'  | 'LED SMD BLUE(LTST-C191TBKT-DE)'                                      | ''             | ''          | ''   | '20170816'
 'LED_YEL/GRE'              | 'SMLF'    | '16-213/G6C-BM2P1B/3T'      | 'IC'     | 'BEYG0127ZA0'(!)  = ''              | ''             | 'BEYG0127ZA0'     |'LED_16213XA'| 'IC'  | 'LED SMD(2P)YEL/GRE(16-213/G6C-BM2P1B/3T)'                            | ''             | ''          | ''   | '20170912'
 'LED_YEL/GRE'              | 'SMLF'    | '16-213/G6C-BM2P1B/3T'      | 'EMPTY'  | 'BEYG0127ZA0'(!)  = ''              | ''             | 'BEYG0127ZA0'     |'LED_16213XA'| 'IO'  | 'LED SMD(2P)YEL/GRE(16-213/G6C-BM2P1B/3T)'                            | ''             | ''          | ''   | '20170912'
 'LED_BLUE'                 | 'SMLF'    | 'LTST-S482TBKT-5A'          | 'IC'     | 'BEBL0174Z00'(!)  = ''              | ''             | 'BEBL0174Z00'     |'LED2S_LTST-S482KRKT-5A'| 'IC'  | 'LED SMD(2P) BLUE(LTST-S482TBKT-5A)'                                  | ''             | ''          | ''   | '20171019'
 'LED_BLUE'                 | 'SMLF'    | 'LTST-S482TBKT-5A'          | 'EMPTY'  | 'BEBL0174Z00'(!)  = ''              | ''             | 'BEBL0174Z00'     |'LED2S_LTST-S482KRKT-5A'| 'IO'  | 'LED SMD(2P) BLUE(LTST-S482TBKT-5A)'                                  | ''             | ''          | ''   | '20171019'
 'LED_GREEN'                | 'SMLF'    | 'LTST-C170KGKT-SR'          | 'IC'     | 'BEGR0024Z00'(!)  = ''              | ''             | 'BEGR0024Z00'     |'LED_170VY_H44'| 'IC'  | 'LED SMD(2P)GREEN(LTST-C170KGKT-SR)'                                  | ''             | ''          | ''   | '20171102'
 'LED_GREEN'                | 'SMLF'    | 'LTST-C170KGKT-SR'          | 'EMPTY'  | 'BEGR0024Z00'(!)  = ''              | ''             | 'BEGR0024Z00'     |'LED_170VY_H44'| 'IO'  | 'LED SMD(2P)GREEN(LTST-C170KGKT-SR)'                                  | ''             | ''          | ''   | '20171102'
 'LED_RED'                  | 'SMLF'    | 'LTST-C170KRKT-5A'          | 'IC'     | 'BERD0015Z00'(!)  = ''              | ''             | 'BERD0015Z00'     |'LED_170VY_H44'| 'IC'  | 'LED SMD(2P)RED(LTST-C170KRKT-5A)'                                    | ''             | ''          | ''   | '20171102'
 'LED_RED'                  | 'SMLF'    | 'LTST-C170KRKT-5A'          | 'EMPTY'  | 'BERD0015Z00'(!)  = ''              | ''             | 'BERD0015Z00'     |'LED_170VY_H44'| 'IO'  | 'LED SMD(2P)RED(LTST-C170KRKT-5A)'                                    | ''             | ''          | ''   | '20171102'
 'LED_ORANGE'               | 'SMLF'    | '16-213/S2C-BM2P1VY/3T'     | 'IC'     | 'BE0R0115Z00'(!)  = ''              | ''             | 'BE0R0115Z00'     |'LED2S_0402XA'| 'IC'  | 'LED SMD (2P) ORA 16-213/S2C-BM2P1VY/3T'                              | ''             | ''          | ''   | '20180129'
 'LED_ORANGE'               | 'SMLF'    | '16-213/S2C-BM2P1VY/3T'     | 'EMPTY'  | 'BE0R0115Z00'(!)  = ''              | ''             | 'BE0R0115Z00'     |'LED2S_0402XA'| 'IO'  | 'LED SMD (2P) ORA 16-213/S2C-BM2P1VY/3T'                              | ''             | ''          | ''   | '20180129'
 'LED_GREEN'                | 'THLF'    | 'LTL-533-11P2T'             | 'IC'     | 'BEGR0004D00'(!)  = ''              | ''             | 'BEGR0004D00'     |'LED2P_LTL102TB8WH006PT'| 'IC'  | 'LED DIP(2P)GREEN(LTL-533-11P2T)'                                     | ''             | ''          | ''   | '20180307'
 'LED_GREEN'                | 'THLF'    | 'LTL-533-11P2T'             | 'EMPTY'  | 'BEGR0004D00'(!)  = ''              | ''             | 'BEGR0004D00'     |'LED2P_LTL102TB8WH006PT'| 'IO'  | 'LED DIP(2P)GREEN(LTL-533-11P2T)'                                     | ''             | ''          | ''   | '20180307'
 'LED_GREEN'                | 'SMLF'    | 'LTST-S482KFKT-SE'          | 'IC'     | 'BEGR0028Z00'(!)  = ''              | 'End of Life'  | 'BEGR0028Z00'     |'LED2S_LTST-S482KFKT-SE_EOL'| 'IC'  | 'LED SMD(2P)GREEN(LTST-S482KFKT-SE)'                                  | ''             | ''          | ''   | '20180411'
 'LED_GREEN'                | 'SMLF'    | 'LTST-S482KFKT-SE'          | 'EMPTY'  | 'BEGR0028Z00'(!)  = ''              | 'End of Life'  | 'BEGR0028Z00'     |'LED2S_LTST-S482KFKT-SE_EOL'| 'IO'  | 'LED SMD(2P)GREEN(LTST-S482KFKT-SE)'                                  | ''             | ''          | ''   | '20180411'
 'LED_BLUE'                 | 'THLF'    | 'LTL42TBN4DHBP-1'           | 'IC'     | 'BEBL0018Z00'(!)  = 'End of Design' | 'Comp-Approve' | 'BEBL0018Z00'     |'LED2P_LTL-14CDJNHBP'| 'IC'  | 'LED DIP(2P)BLUE(LTL42TBN4DHBP-1)'                                    | ''             | ''          | ''   | '20180412'
 'LED_BLUE'                 | 'THLF'    | 'LTL42TBN4DHBP-1'           | 'EMPTY'  | 'BEBL0018Z00'(!)  = 'End of Design' | 'Comp-Approve' | 'BEBL0018Z00'     |'LED2P_LTL-14CDJNHBP'| 'IO'  | 'LED DIP(2P)BLUE(LTL42TBN4DHBP-1)'                                    | ''             | ''          | ''   | '20180412'
 'LED_RED'                  | 'THLF'    | 'LTL-42NEW8DHBP-1'          | 'IC'     | 'BERD0014Z00'(!)  = ''              | 'End of Life'  | 'BERD0014Z00'     |'LED2P_LTL-14CDJNHBP_EOL'| 'IC'  | 'LED DIP(2P)RED(LTL-42NEW8DHBP-1)'                                    | ''             | ''          | ''   | '20180412'
 'LED_RED'                  | 'THLF'    | 'LTL-42NEW8DHBP-1'          | 'EMPTY'  | 'BERD0014Z00'(!)  = ''              | 'End of Life'  | 'BERD0014Z00'     |'LED2P_LTL-14CDJNHBP_EOL'| 'IO'  | 'LED DIP(2P)RED(LTL-42NEW8DHBP-1)'                                    | ''             | ''          | ''   | '20180412'
 'LED_ORANGE'               | 'SMLF'    | 'LTST-C171KFKT'             | 'IC'     | 'BE0R0002Z00'(!)  = ''              | ''             | 'BE0R0002Z00'     |'LED_C171GKT'| 'IC'  | 'LED SMD(2P)ORANGE(LTST-C171KFKT)'                                    | ''             | ''          | ''   | '20180418'
 'LED_ORANGE'               | 'SMLF'    | 'LTST-C171KFKT'             | 'EMPTY'  | 'BE0R0002Z00'(!)  = ''              | ''             | 'BE0R0002Z00'     |'LED_C171GKT'| 'IO'  | 'LED SMD(2P)ORANGE(LTST-C171KFKT)'                                    | ''             | ''          | ''   | '20180418'
 'LED BLUE'                 | 'SMLF'    | '42-21 UBC/C470/TR8'        | 'IC'     | 'BEBL0037Z01'(!)  = ''              | ''             | 'BEBL0037Z01'     |'LED_4221'| 'IC'  | 'LED SMD BLUE 42-21 UBC/C470/TR8'                                     | ''             | ''          | ''   | '20180607'
 'LED BLUE'                 | 'SMLF'    | '42-21 UBC/C470/TR8'        | 'EMPTY'  | 'BEBL0037Z01'(!)  = ''              | ''             | 'BEBL0037Z01'     |'LED_4221'| 'IO'  | 'LED SMD BLUE 42-21 UBC/C470/TR8'                                     | ''             | ''          | ''   | '20180607'
 'LED_BLUE'                 | 'SMLF'    | '67-21/BHC-FQ1R2F/2T'       | 'IC'     | 'BEBL0231Z00'(!)  = ''              | ''             | 'BEBL0231Z00'     |'LED2S_67-21BHC-FQ1R2F2T'| 'IC'  | 'LED SMD(2P) BLUE(67-21/BHC-FQ1R2F/2T)'                               | ''             | ''          | ''   | '20180625'
 'LED_BLUE'                 | 'SMLF'    | '67-21/BHC-FQ1R2F/2T'       | 'EMPTY'  | 'BEBL0231Z00'(!)  = ''              | ''             | 'BEBL0231Z00'     |'LED2S_67-21BHC-FQ1R2F2T'| 'IO'  | 'LED SMD(2P) BLUE(67-21/BHC-FQ1R2F/2T)'                               | ''             | ''          | ''   | '20180625'
 'LED_ORANGE'               | 'SMLF'    | '67-21/S2C-AQ2S1B/2T'       | 'IC'     | 'BE0R0013Z00'(!)  = ''              | ''             | 'BE0R0013Z00'     |'LED2S_67-21BHC-FQ1R2F2T'| 'IC'  | 'LED SMD(2P)ORANGE(67-21/S2C-AQ2S1B/2T)'                              | ''             | ''          | ''   | '20180718'
 'LED_ORANGE'               | 'SMLF'    | '67-21/S2C-AQ2S1B/2T'       | 'EMPTY'  | 'BE0R0013Z00'(!)  = ''              | ''             | 'BE0R0013Z00'     |'LED2S_67-21BHC-FQ1R2F2T'| 'IO'  | 'LED SMD(2P)ORANGE(67-21/S2C-AQ2S1B/2T)'                              | ''             | ''          | ''   | '20180718'
 'LED_YELL/GRE'             | 'SMLF'    | '27-21/G6C-AN2Q1B/3C'       | 'IC'     | 'BEYG0146ZA0'(!)  = ''              | ''             | 'BEYG0146ZA0'     |'LED2S_27-21G6C-AN2Q1B3C'| 'IC'  | 'LED SMD(2P)YELL/GRE(27-21/G6C-AN2Q1B/3C'                             | ''             | ''          | ''   | '20180814'
 'LED_YELL/GRE'             | 'SMLF'    | '27-21/G6C-AN2Q1B/3C'       | 'EMPTY'  | 'BEYG0146ZA0'(!)  = ''              | ''             | 'BEYG0146ZA0'     |'LED2S_27-21G6C-AN2Q1B3C'| 'IO'  | 'LED SMD(2P)YELL/GRE(27-21/G6C-AN2Q1B/3C'                             | ''             | ''          | ''   | '20180814'
 'LED_BLUE'                 | 'THLF'    | 'LTL42TB6NH184T'            | 'IC'     | 'BEBL0236D00'(!)  = ''              | ''             | 'BEBL0236D00'     |'LED2P_LTL42TB6NH184T'| 'IC'  | 'LED DIP(2P)BLUE(LTL42TB6NH184T)'                                     | ''             | ''          | ''   | '20180910'
 'LED_BLUE'                 | 'THLF'    | 'LTL42TB6NH184T'            | 'EMPTY'  | 'BEBL0236D00'(!)  = ''              | ''             | 'BEBL0236D00'     |'LED2P_LTL42TB6NH184T'| 'IO'  | 'LED DIP(2P)BLUE(LTL42TB6NH184T)'                                     | ''             | ''          | ''   | '20180910'
 'LED_RED'                  | 'THLF'    | 'LTL-42NEW8DH184T'          | 'IC'     | 'BERD0142Z00'(!)  = ''              | ''             | 'BERD0142Z00'     |'LED2P_LTL42TB6NH184T'| 'IC'  | 'LED DIP(2P)RED(LTL-42NEW8DH184T)'                                    | ''             | ''          | ''   | '20181001'
 'LED_RED'                  | 'THLF'    | 'LTL-42NEW8DH184T'          | 'EMPTY'  | 'BERD0142Z00'(!)  = ''              | ''             | 'BERD0142Z00'     |'LED2P_LTL42TB6NH184T'| 'IO'  | 'LED DIP(2P)RED(LTL-42NEW8DH184T)'                                    | ''             | ''          | ''   | '20181001'
 'LED_YELLOW'               | 'THLF'    | 'LTL-42NSV8DHBPT'           | 'IC'     | 'BEYL0003D00'(!)  = ''              | ''             | 'BEYL0003D00'     |'LED2P_LTL-14CDJNHBP'| 'IC'  | 'LED DIP(2P)YELLOW(LTL-42NSV8DHBPT)'                                  | ''             | ''          | ''   | '20181116'
 'LED_YELLOW'               | 'THLF'    | 'LTL-42NSV8DHBPT'           | 'EMPTY'  | 'BEYL0003D00'(!)  = ''              | ''             | 'BEYL0003D00'     |'LED2P_LTL-14CDJNHBP'| 'IO'  | 'LED DIP(2P)YELLOW(LTL-42NSV8DHBPT)'                                  | ''             | ''          | ''   | '20181116'
 'LED_ORANGE'               | 'SMLF'    | '67-21/S2C-AS1T1/2T'        | 'IC'     | 'BE0R0127Z00'(!)  = ''              | ''             | 'BE0R0127Z00'     |'LED2S_67-21S2C-AS1T12T'| 'IC'  | 'LED SMD(2P)ORANGE(67-21/S2C-AS1T1/2T)'                               | ''             | ''          | ''   | '20190111'
 'LED_ORANGE'               | 'SMLF'    | '67-21/S2C-AS1T1/2T'        | 'EMPTY'  | 'BE0R0127Z00'(!)  = ''              | ''             | 'BE0R0127Z00'     |'LED2S_67-21S2C-AS1T12T'| 'IO'  | 'LED SMD(2P)ORANGE(67-21/S2C-AS1T1/2T)'                               | ''             | ''          | ''   | '20190111'
 'LED2S_SIR57-21C/L388/TR8' | 'SMLF'    | 'SIR57-21C/L388/TR8'        | 'IC'     | 'BE000082ZR0'(!)  = ''              | ''             | 'BE000082ZR0'     |'LED2S_SIR57-21CL388TR8'| 'IC'  | 'LED SMD(2P)INFRARED(SIR57-21C/L388/TR8)'                             | ''             | ''          | ''   | '20190111'
 'LED2S_SIR57-21C/L388/TR8' | 'SMLF'    | 'SIR57-21C/L388/TR8'        | 'EMPTY'  | 'BE000082ZR0'(!)  = ''              | ''             | 'BE000082ZR0'     |'LED2S_SIR57-21CL388TR8'| 'IO'  | 'LED SMD(2P)INFRARED(SIR57-21C/L388/TR8)'                             | ''             | ''          | ''   | '20190111'
 'LED_GREEN'                | 'SMLF'    | '27-21SYGC/S530-E2/TR8'     | 'IC'     | 'BEGR0150Z05'(!)  = ''              | ''             | 'BEGR0150Z05'     |'LED2S_27-21UYC'| 'IC'  | 'LED SMD(2P)GREEN(27-21SYGC/S530-E2/TR8)'                             | ''             | ''          | ''   | '20150520'
 'LED_GREEN'                | 'SMLF'    | '27-21SYGC/S530-E2/TR8'     | 'EMPTY'  | 'BEGR0150Z05'(!)  = ''              | ''             | 'BEGR0150Z05'     |'LED2S_27-21UYC'| 'IO'  | 'LED SMD(2P)GREEN(27-21SYGC/S530-E2/TR8)'                             | ''             | ''          | ''   | '20150520'
 'LED_ORANGE'               | 'THLF'    | 'LTL42NKFKNNHBP-1'          | 'IC'     | 'BE0R0130D00'(!)  = ''              | ''             | 'BE0R0130D00'     |'LED2P_LTL-14CDJNHBP'| 'IC'  | 'LED DIP(2P)ORANGE(LTL42NKFKNNHBP-1)'                                 | ''             | ''          | ''   | '20190131'
 'LED_ORANGE'               | 'THLF'    | 'LTL42NKFKNNHBP-1'          | 'EMPTY'  | 'BE0R0130D00'(!)  = ''              | ''             | 'BE0R0130D00'     |'LED2P_LTL-14CDJNHBP'| 'IO'  | 'LED DIP(2P)ORANGE(LTL42NKFKNNHBP-1)'                                 | ''             | ''          | ''   | '20190131'
 'LED_BLUE'                 | 'THLF'    | 'LTL102TB8WH006PT'          | 'IC'     | 'BEBL0003D00'(!)  = ''              | ''             | 'BEBL0003D00'     |'LED2P_LTL102TB8WH006PT'| 'IC'  | 'LED DIP(2P)BLUE(LTL102TB8WH006PT)'                                   | ''             | ''          | ''   | '20180307'
 'LED_BLUE'                 | 'THLF'    | 'LTL102TB8WH006PT'          | 'EMPTY'  | 'BEBL0003D00'(!)  = ''              | ''             | 'BEBL0003D00'     |'LED2P_LTL102TB8WH006PT'| 'IO'  | 'LED DIP(2P)BLUE(LTL102TB8WH006PT)'                                   | ''             | ''          | ''   | '20180307'
 'LED_BLUE'                 | 'THLF'    | 'LTL42FTBG9JH213T'          | 'IC'     | 'BEBL0186D00'(!)  = ''              | ''             | 'BEBL0186D00'     |'LED2P_LTL-42FSVADH213T'| 'IC'  | 'LED DIP(2P)BLUE(LTL42FTBG9JH213T)'                                   | ''             | ''          | ''   | '20190410'
 'LED_BLUE'                 | 'THLF'    | 'LTL42FTBG9JH213T'          | 'EMPTY'  | 'BEBL0186D00'(!)  = ''              | ''             | 'BEBL0186D00'     |'LED2P_LTL-42FSVADH213T'| 'IO'  | 'LED DIP(2P)BLUE(LTL42FTBG9JH213T)'                                   | ''             | ''          | ''   | '20190410'
 'LED_YELLOW'               | 'THLF'    | 'LTL-42FSVADH213T'          | 'IC'     | 'BEYL0149D00'(!)  = ''              | ''             | 'BEYL0149D00'     |'LED2P_LTL-42FSVADH213T'| 'IC'  | 'LED DIP(2P)YELLOW(LTL-42FSVADH213T)'                                 | ''             | ''          | ''   | '20190410'
 'LED_YELLOW'               | 'THLF'    | 'LTL-42FSVADH213T'          | 'EMPTY'  | 'BEYL0149D00'(!)  = ''              | ''             | 'BEYL0149D00'     |'LED2P_LTL-42FSVADH213T'| 'IO'  | 'LED DIP(2P)YELLOW(LTL-42FSVADH213T)'                                 | ''             | ''          | ''   | '20190410'
 'LED_YEL/GREEN'            | 'SMLF'    | 'QSME-C19Z'                 | 'IC'     | 'BEYL0135Z00'(!)  = 'End of Design' | 'Comp-Approve' | 'BEYL0135Z00'     |'LED_1921'| 'IC'  | 'LED SMD(2P) YELGREEN(QSME-C19Z)'                                     | ''             | ''          | ''   | '20190606'
 'LED_YEL/GREEN'            | 'SMLF'    | 'QSME-C19Z'                 | 'EMPTY'  | 'BEYL0135Z00'(!)  = 'End of Design' | 'Comp-Approve' | 'BEYL0135Z00'     |'LED_1921'| 'IO'  | 'LED SMD(2P) YELGREEN(QSME-C19Z)'                                     | ''             | ''          | ''   | '20190606'
 'LED_ORANGE'               | 'SMLF'    | 'QSML-C19Q'                 | 'IC'     | 'BE0R0126Z00'(!)  = ''              | ''             | 'BE0R0126Z00'     |'LED_1921'| 'IC'  | 'LED SMD(2P) ORANGE(QSML-C19Q)'                                       | ''             | ''          | ''   | '20190606'
 'LED_ORANGE'               | 'SMLF'    | 'QSML-C19Q'                 | 'EMPTY'  | 'BE0R0126Z00'(!)  = ''              | ''             | 'BE0R0126Z00'     |'LED_1921'| 'IO'  | 'LED SMD(2P) ORANGE(QSML-C19Q)'                                       | ''             | ''          | ''   | '20190606'
 'LED_BLUE'                 | 'SMLF'    | 'QSMR-C130-QRBC0'           | 'IC'     | 'BEBL0184Z00'(!)  = ''              | ''             | 'BEBL0184Z00'     |'LED2S_QSMR-C130-QRBC0'| 'IC'  | 'LED SMD(2P) BLUE(QSMR-C130-QRBC0)'                                   | ''             | ''          | ''   | '20190610'
 'LED_BLUE'                 | 'SMLF'    | 'QSMR-C130-QRBC0'           | 'EMPTY'  | 'BEBL0184Z00'(!)  = ''              | ''             | 'BEBL0184Z00'     |'LED2S_QSMR-C130-QRBC0'| 'IO'  | 'LED SMD(2P) BLUE(QSMR-C130-QRBC0)'                                   | ''             | ''          | ''   | '20190610'
 'LED_BLUE'                 | 'SMLF'    | 'LTST-C990TBKT'             | 'IC'     | 'BEBL0189Z00'(!)  = ''              | ''             | 'BEBL0189Z00'     |'LED2S_QSMR-C130-QRBC0_H39'| 'IC'  | 'LED SMD(2P)BLUE(LTST-C990TBKT)'                                      | ''             | ''          | ''   | '20190805'
 'LED_BLUE'                 | 'SMLF'    | 'LTST-C990TBKT'             | 'EMPTY'  | 'BEBL0189Z00'(!)  = ''              | ''             | 'BEBL0189Z00'     |'LED2S_QSMR-C130-QRBC0_H39'| 'IO'  | 'LED SMD(2P)BLUE(LTST-C990TBKT)'                                      | ''             | ''          | ''   | '20190805'
 'LED_ORANGE'               | 'SMLF'    | 'LTST-C990KFKT'             | 'IC'     | 'BE0R0134Z00'(!)  = ''              | ''             | 'BE0R0134Z00'     |'LED2S_QSMR-C130-QRBC0_H39'| 'IC'  | 'LED SMD(2P)ORANGE(LTST-C990KFKT)'                                    | ''             | ''          | ''   | '20190805'
 'LED_ORANGE'               | 'SMLF'    | 'LTST-C990KFKT'             | 'EMPTY'  | 'BE0R0134Z00'(!)  = ''              | ''             | 'BE0R0134Z00'     |'LED2S_QSMR-C130-QRBC0_H39'| 'IO'  | 'LED SMD(2P)ORANGE(LTST-C990KFKT)'                                    | ''             | ''          | ''   | '20190805'
 'LED_BLUE'                 | 'SMLF'    | 'LTST-C193TBKT-5A'          | 'IC'     | 'BEBL0182Z00'(!)  = ''              | ''             | 'BEBL0182Z00'     |'LED_19217'| 'IC'  | 'LED SMD(2P) BLUE LTST-C193TBKT-5A'                                   | ''             | ''          | ''   | '20190925'
 'LED_BLUE'                 | 'SMLF'    | 'LTST-C193TBKT-5A'          | 'EMPTY'  | 'BEBL0182Z00'(!)  = ''              | ''             | 'BEBL0182Z00'     |'LED_19217'| 'IO'  | 'LED SMD(2P) BLUE LTST-C193TBKT-5A'                                   | ''             | ''          | ''   | '20190925'
 'LED_GREEN'                | 'SMLF'    | 'LTST-T180TGKT'             | 'IC'     | 'BEGR0365Z00'(!)  = ''              | ''             | 'BEGR0365Z00'     |'LED2S_LTST-T180TGKT'| 'IC'  | 'LED SMD(2P)GREEN(LTST-T180TGKT)'                                     | ''             | ''          | ''   | '20191001'
 'LED_GREEN'                | 'SMLF'    | 'LTST-T180TGKT'             | 'EMPTY'  | 'BEGR0365Z00'(!)  = ''              | ''             | 'BEGR0365Z00'     |'LED2S_LTST-T180TGKT'| 'IO'  | 'LED SMD(2P)GREEN(LTST-T180TGKT)'                                     | ''             | ''          | ''   | '20191001'
 'LED_RED'                  | 'THLF'    | 'LTL-42NEW8DHBPT'           | 'IC'     | 'BERD0014D00'(!)  = ''              | ''             | 'BERD0014D00'     |'LED2P_LTL-42NEW8DHBPT'| 'IC'  | 'LED DIP(2P)RED(LTL-42NEW8DHBPT)'                                     | ''             | ''          | ''   | '20191031'
 'LED_RED'                  | 'THLF'    | 'LTL-42NEW8DHBPT'           | 'EMPTY'  | 'BERD0014D00'(!)  = ''              | ''             | 'BERD0014D00'     |'LED2P_LTL-42NEW8DHBPT'| 'IO'  | 'LED DIP(2P)RED(LTL-42NEW8DHBPT)'                                     | ''             | ''          | ''   | '20191031'
 'LED_YEL/GR'               | 'SMLF'    | '19-21SYGC/S530-E3/TR8'     | 'IC'     | 'BEYG0149ZA0'(!)  = ''              | ''             | 'BEYG0149ZA0'     |'LED2S_19-21SYGC'| 'IC'  | 'LED SMD(2P)YEL/GR 19-21SYGC/S530-E3/TR8'                             | ''             | ''          | ''   | '20191211'
 'LED_YEL/GR'               | 'SMLF'    | '19-21SYGC/S530-E3/TR8'     | 'EMPTY'  | 'BEYG0149ZA0'(!)  = ''              | ''             | 'BEYG0149ZA0'     |'LED2S_19-21SYGC'| 'IO'  | 'LED SMD(2P)YEL/GR 19-21SYGC/S530-E3/TR8'                             | ''             | ''          | ''   | '20191211'
 'LED_GREEN'                | 'SMLF'    | 'LTST-C193TGKT'             | 'IC'     | 'BEGR0314Z00'(!)  = ''              | ''             | 'BEGR0314Z00'     |'LED_19217'| 'IC'  | 'LED SMD(2P)GREEN(LTST-C193TGKT)'                                     | ''             | ''          | ''   | '20191216'
 'LED_GREEN'                | 'SMLF'    | 'LTST-C193TGKT'             | 'EMPTY'  | 'BEGR0314Z00'(!)  = ''              | ''             | 'BEGR0314Z00'     |'LED_19217'| 'IO'  | 'LED SMD(2P)GREEN(LTST-C193TGKT)'                                     | ''             | ''          | ''   | '20191216'
 'LED_BLUE'                 | 'SMLF'    | 'LTST-C281TBKT-5A'          | 'IC'     | 'BEBL0172Z00'(!)  = ''              | ''             | 'BEBL0172Z00'     |'LED2S_0402'| 'IC'  | 'LED SMD(2P) BLUE(LTST-C281TBKT-5A)'                                  | ''             | ''          | ''   | '20121120'
 'LED_BLUE'                 | 'SMLF'    | 'LTST-C281TBKT-5A'          | 'EMPTY'  | 'BEBL0172Z00'(!)  = ''              | ''             | 'BEBL0172Z00'     |'LED2S_0402'| 'IO'  | 'LED SMD(2P) BLUE(LTST-C281TBKT-5A)'                                  | ''             | ''          | ''   | '20121120'
 'LED_YELLOW'               | 'SMLF'    | 'LTST-C190KSKT-P'           | 'IC'     | 'BEYL0159Z00'(!)  = ''              | ''             | 'BEYL0159Z00'     |'LED_1921XA'| 'IC'  | 'LED SMD(2P)YELLOW(LTST-C190KSKT-P)'                                  | ''             | ''          | ''   | '20200214'
 'LED_YELLOW'               | 'SMLF'    | 'LTST-C190KSKT-P'           | 'EMPTY'  | 'BEYL0159Z00'(!)  = ''              | ''             | 'BEYL0159Z00'     |'LED_1921XA'| 'IO'  | 'LED SMD(2P)YELLOW(LTST-C190KSKT-P)'                                  | ''             | ''          | ''   | '20200214'
 'LED_BLUE'                 | 'SMLF'    | '12-215/BHC-YMNRY/3C'       | 'IC'     | 'BEBL0261Z00'(!)  = ''              | ''             | 'BEBL0261Z00'     |'LED2S_12-215BHC-YMNRY3C'| 'IC'  | 'LED SMD(2P)BLUE(12-215/BHC-YMNRY/3C)'                                | ''             | ''          | ''   | '20200311'
 'LED_BLUE'                 | 'SMLF'    | '12-215/BHC-YMNRY/3C'       | 'EMPTY'  | 'BEBL0261Z00'(!)  = ''              | ''             | 'BEBL0261Z00'     |'LED2S_12-215BHC-YMNRY3C'| 'IO'  | 'LED SMD(2P)BLUE(12-215/BHC-YMNRY/3C)'                                | ''             | ''          | ''   | '20200311'
 'LED_RED'                  | 'SMLF'    | 'LTST-S270KRKT'             | 'IC'     | 'BERD0061Z00'(!)  = ''              | ''             | 'BERD0061Z00'     |'LED2S_LTST-S270KRKT'| 'IC'  | 'LED SMD(2P) RED(LTST-S270KRKT)'                                      | ''             | ''          | ''   | '20200316'
 'LED_RED'                  | 'SMLF'    | 'LTST-S270KRKT'             | 'EMPTY'  | 'BERD0061Z00'(!)  = ''              | ''             | 'BERD0061Z00'     |'LED2S_LTST-S270KRKT'| 'IO'  | 'LED SMD(2P) RED(LTST-S270KRKT)'                                      | ''             | ''          | ''   | '20200316'
 'LED_BLUE'                 | 'SMLF'    | 'LTL-M11TB1H300Q'           | 'IC'     | 'BEBL0262Z00'(!)  = ''              | ''             | 'BEBL0262Z00'     |'LED2S_LTL-M11KS1H300Q'| 'IC'  | 'LED SMD(2P)BLUE(LTL-M11TB1H300Q)'                                    | ''             | ''          | ''   | '20200407'
 'LED_BLUE'                 | 'SMLF'    | 'LTL-M11TB1H300Q'           | 'EMPTY'  | 'BEBL0262Z00'(!)  = ''              | ''             | 'BEBL0262Z00'     |'LED2S_LTL-M11KS1H300Q'| 'IO'  | 'LED SMD(2P)BLUE(LTL-M11TB1H300Q)'                                    | ''             | ''          | ''   | '20200407'
 'LED_YELLOW'               | 'SMLF'    | 'LTL-M11KS1H300Q'           | 'IC'     | 'BEYL0163Z00'(!)  = ''              | ''             | 'BEYL0163Z00'     |'LED2S_LTL-M11KS1H300Q'| 'IC'  | 'LED SMD(2P)YELLOW(LTL-M11KS1H300Q)'                                  | ''             | ''          | ''   | '20200408'
 'LED_YELLOW'               | 'SMLF'    | 'LTL-M11KS1H300Q'           | 'EMPTY'  | 'BEYL0163Z00'(!)  = ''              | ''             | 'BEYL0163Z00'     |'LED2S_LTL-M11KS1H300Q'| 'IO'  | 'LED SMD(2P)YELLOW(LTL-M11KS1H300Q)'                                  | ''             | ''          | ''   | '20200408'
 'LED_GREEN'                | 'THLF'    | 'LTL-42FGYADH213T'          | 'IC'     | 'BEGR0380Z00'(!)  = ''              | ''             | 'BEGR0380Z00'     |'LED2P_LTL-42FSVADH213T'| 'IC'  | 'LED DIP(2P)GREEN (LTL-42FGYADH213T)'                                 | ''             | ''          | ''   | '20200827'
 'LED_GREEN'                | 'THLF'    | 'LTL-42FGYADH213T'          | 'EMPTY'  | 'BEGR0380Z00'(!)  = ''              | ''             | 'BEGR0380Z00'     |'LED2P_LTL-42FSVADH213T'| 'IO'  | 'LED DIP(2P)GREEN (LTL-42FGYADH213T)'                                 | ''             | ''          | ''   | '20200827'
 'LED_ORANGE'               | 'THLF'    | 'LTL-42FFEADH213T'          | 'IC'     | 'BE0R0140Z00'(!)  = ''              | ''             | 'BE0R0140Z00'     |'LED2P_LTL-42FSVADH213T'| 'IC'  | 'LED DIP(2P)ORANGE(LTL-42FFEADH213T)'                                 | ''             | ''          | ''   | '20200903'
 'LED_ORANGE'               | 'THLF'    | 'LTL-42FFEADH213T'          | 'EMPTY'  | 'BE0R0140Z00'(!)  = ''              | ''             | 'BE0R0140Z00'     |'LED2P_LTL-42FSVADH213T'| 'IO'  | 'LED DIP(2P)ORANGE(LTL-42FFEADH213T)'                                 | ''             | ''          | ''   | '20200903'
 'LED_RED'                  | 'THLF'    | 'LTL-42FRC5JH213T'          | 'IC'     | 'BERD0171Z00'(!)  = ''              | ''             | 'BERD0171Z00'     |'LED2P_LTL-42FSVADH213T'| 'IC'  | 'LED DIP(2P)RED (LTL-42FRC5JH213T)'                                   | ''             | ''          | ''   | '20200903'
 'LED_RED'                  | 'THLF'    | 'LTL-42FRC5JH213T'          | 'EMPTY'  | 'BERD0171Z00'(!)  = ''              | ''             | 'BERD0171Z00'     |'LED2P_LTL-42FSVADH213T'| 'IO'  | 'LED DIP(2P)RED (LTL-42FRC5JH213T)'                                   | ''             | ''          | ''   | '20200903'
 'LED_BLUE'                 | 'SMLF'    | 'LTL-M11TB1H310Q'           | 'IC'     | 'BEBL0267Z00'(!)  = ''              | ''             | 'BEBL0267Z00'     |'LED2S_LTL-M11TB1H310Q'| 'IC'  | 'LED SMD(2P)BLUE(LTL-M11TB1H310Q)'                                    | ''             | ''          | ''   | '20200924'
 'LED_BLUE'                 | 'SMLF'    | 'LTL-M11TB1H310Q'           | 'EMPTY'  | 'BEBL0267Z00'(!)  = ''              | ''             | 'BEBL0267Z00'     |'LED2S_LTL-M11TB1H310Q'| 'IO'  | 'LED SMD(2P)BLUE(LTL-M11TB1H310Q)'                                    | ''             | ''          | ''   | '20200924'
 'LED_YELLOW'               | 'SMLF'    | 'LTL-M11KS1H310Q'           | 'IC'     | 'BEYL0169Z00'(!)  = ''              | ''             | 'BEYL0169Z00'     |'LED2S_LTL-M11TB1H310Q'| 'IC'  | 'LED SMD(2P)YELLOW(LTL-M11KS1H310Q)'                                  | ''             | ''          | ''   | '20200924'
 'LED_YELLOW'               | 'SMLF'    | 'LTL-M11KS1H310Q'           | 'EMPTY'  | 'BEYL0169Z00'(!)  = ''              | ''             | 'BEYL0169Z00'     |'LED2S_LTL-M11TB1H310Q'| 'IO'  | 'LED SMD(2P)YELLOW(LTL-M11KS1H310Q)'                                  | ''             | ''          | ''   | '20200924'
 'LED_GREEN'                | 'SMLF'    | 'LTST-C171TGKT'             | 'IC'     | 'BEGR0381Z00'(!)  = ''              | ''             | 'BEGR0381Z00'     |'LED_C171GKT'| 'IC'  | 'LED SMD(2P)GREEN(LTST-C171TGKT)'                                     | ''             | ''          | ''   | '20200928'
 'LED_GREEN'                | 'SMLF'    | 'LTST-C171TGKT'             | 'EMPTY'  | 'BEGR0381Z00'(!)  = ''              | ''             | 'BEGR0381Z00'     |'LED_C171GKT'| 'IO'  | 'LED SMD(2P)GREEN(LTST-C171TGKT)'                                     | ''             | ''          | ''   | '20200928'
 'LED_BLUE'                 | 'THLF'    | 'LTL42TB6NHBPT'             | 'IC'     | 'BEBL0265D00'(!)  = ''              | ''             | 'BEBL0265D00'     |'LED2P_LTL-14CDJNHBP'| 'IC'  | 'LED DIP(2P) BLUE (LTL42TB6NHBPT)'                                    | ''             | ''          | ''   | '20201013'
 'LED_BLUE'                 | 'THLF'    | 'LTL42TB6NHBPT'             | 'EMPTY'  | 'BEBL0265D00'(!)  = ''              | ''             | 'BEBL0265D00'     |'LED2P_LTL-14CDJNHBP'| 'IO'  | 'LED DIP(2P) BLUE (LTL42TB6NHBPT)'                                    | ''             | ''          | ''   | '20201013'
 'LED_BLUE'                 | 'SMLF'    | 'LTST-M670UBKT'             | 'IC'     | 'BEBL0268Z00'(!)  = ''              | ''             | 'BEBL0268Z00'     |'LED2S_LTST-M670UBKT'| 'IC'  | 'LED SMD(2P)BLUE(LTST-M670UBKT)'                                      | ''             | ''          | ''   | '20201023'
 'LED_BLUE'                 | 'SMLF'    | 'LTST-M670UBKT'             | 'EMPTY'  | 'BEBL0268Z00'(!)  = ''              | ''             | 'BEBL0268Z00'     |'LED2S_LTST-M670UBKT'| 'IO'  | 'LED SMD(2P)BLUE(LTST-M670UBKT)'                                      | ''             | ''          | ''   | '20201023'
 'LED_GREEN'                | 'SMLF'    | '16-219A/GHC-YP2R1QY/3T'    | 'IC'     | 'BEGR0034Z00'(!)  = ''              | ''             | 'BEGR0034Z00'     |'LED2S_16-219AGHC-YP2R1QY3T'| 'IC'  | 'LED SMD(2P)GREEN(16-219A/GHC-YP2R1QY/3T)'                            | ''             | ''          | ''   | '20210819'
 'LED_GREEN'                | 'SMLF'    | '16-219A/GHC-YP2R1QY/3T'    | 'EMPTY'  | 'BEGR0034Z00'(!)  = ''              | ''             | 'BEGR0034Z00'     |'LED2S_16-219AGHC-YP2R1QY3T'| 'IO'  | 'LED SMD(2P)GREEN(16-219A/GHC-YP2R1QY/3T)'                            | ''             | ''          | ''   | '20210819'
 'LED_YELLOWGREEN'          | 'SMLF'    | 'LTST-C281KGKT-Q'           | 'IC'     | 'BEYL0142Z00'(!)  = ''              | ''             | 'BEYL0142Z00'     |'LED2S_0402'| 'IC'  | 'LED SMD(2P)YELLOWGREEN(LTST-C281KGKT-Q)'                             | ''             | ''          | ''   | '20210819'
 'LED_YELLOWGREEN'          | 'SMLF'    | 'LTST-C281KGKT-Q'           | 'EMPTY'  | 'BEYL0142Z00'(!)  = ''              | ''             | 'BEYL0142Z00'     |'LED2S_0402'| 'IO'  | 'LED SMD(2P)YELLOWGREEN(LTST-C281KGKT-Q)'                             | ''             | ''          | ''   | '20210819'
 'LED_YELLOW'               | 'SMLF'    | '12-215/Y2C-CP1Q2B/3C'      | 'IC'     | 'BEYL0178Z00'(!)  = ''              | ''             | 'BEYL0178Z00'     |'LED2S_12-215BHC-YMNRY3C'| 'IC'  | 'LED SMD(2P)YELLOW (12-215/Y2C-CP1Q2B/3C)'                            | ''             | ''          | ''   | '20210924'
 'LED_YELLOW'               | 'SMLF'    | '12-215/Y2C-CP1Q2B/3C'      | 'EMPTY'  | 'BEYL0178Z00'(!)  = ''              | ''             | 'BEYL0178Z00'     |'LED2S_12-215BHC-YMNRY3C'| 'IO'  | 'LED SMD(2P)YELLOW (12-215/Y2C-CP1Q2B/3C)'                            | ''             | ''          | ''   | '20210924'
 'LED_GREEN'                | 'SMLF'    | 'LTST-C193TGKT-F'           | 'IC'     | 'BEGR0392Z00'(!)  = ''              | ''             | 'BEGR0392Z00'     |'LED_19217'| 'IC'  | 'LED SMD(2P)GREEN LTST-C193TGKT-F'                                    | ''             | ''          | ''   | '20211020'
 'LED_GREEN'                | 'SMLF'    | 'LTST-C193TGKT-F'           | 'EMPTY'  | 'BEGR0392Z00'(!)  = ''              | ''             | 'BEGR0392Z00'     |'LED_19217'| 'IO'  | 'LED SMD(2P)GREEN LTST-C193TGKT-F'                                    | ''             | ''          | ''   | '20211020'
 'LED_RED'                  | 'SMLF'    | '16-213/R8C-AP1Q2B/3T'      | 'IC'     | 'BERD0092Z00'(!)  = ''              | ''             | 'BERD0092Z00'     |'LED_16213XA'| 'IC'  | 'LED SMD(2P) RED(16-213/R8C-AP1Q2B/3T)'                               | ''             | ''          | ''   | '20211022'
 'LED_RED'                  | 'SMLF'    | '16-213/R8C-AP1Q2B/3T'      | 'EMPTY'  | 'BERD0092Z00'(!)  = ''              | ''             | 'BERD0092Z00'     |'LED_16213XA'| 'IO'  | 'LED SMD(2P) RED(16-213/R8C-AP1Q2B/3T)'                               | ''             | ''          | ''   | '20211022'
 'LED_BLUE'                 | 'SMLF'    | '17-21/BHC-AN1P2/3T'        | 'IC'     | 'BEBL0051Z04'(!)  = 'End of Design' | 'Comp-Approve' | 'BEBL0051Z04'     |'LED2S_17-21BHC-AP1Q23TXA'| 'IC'  | 'LED SMD(2P) BLUE(BHC-AN1P2/3T)'                                      | ''             | ''          | ''   | '20211209'
 'LED_BLUE'                 | 'SMLF'    | '17-21/BHC-AN1P2/3T'        | 'EMPTY'  | 'BEBL0051Z04'(!)  = 'End of Design' | 'Comp-Approve' | 'BEBL0051Z04'     |'LED2S_17-21BHC-AP1Q23TXA'| 'IO'  | 'LED SMD(2P) BLUE(BHC-AN1P2/3T)'                                      | ''             | ''          | ''   | '20211209'
 'LED_YELLOW'               | 'THLF'    | 'LTL-R42FSFADH213T'         | 'IC'     | 'BEYL0182D00'(!)  = ''              | ''             | 'BEYL0182D00'     |'LED2P_LTL-R42FSFADH213T'| 'IC'  | 'LED DIP(2P)YELLOW(LTL-R42FSFADH213T)'                                | ''             | ''          | ''   | '20220830'
 'LED_YELLOW'               | 'THLF'    | 'LTL-R42FSFADH213T'         | 'EMPTY'  | 'BEYL0182D00'(!)  = ''              | ''             | 'BEYL0182D00'     |'LED2P_LTL-R42FSFADH213T'| 'IO'  | 'LED DIP(2P)YELLOW(LTL-R42FSFADH213T)'                                | ''             | ''          | ''   | '20220830'
 'LED_ORANGE'               | 'THLF'    | 'LTL-42FKFDH184T'           | 'IC'     | 'BE0R0143D00'(!)  = ''              | ''             | 'BE0R0143D00'     |'LED2P_LTL-42FKFDH184T'| 'IC'  | 'LED DIP(2P)ORANGE(LTL-42FKFDH184T)'                                  | ''             | ''          | ''   | '20220207'
 'LED_ORANGE'               | 'THLF'    | 'LTL-42FKFDH184T'           | 'EMPTY'  | 'BE0R0143D00'(!)  = ''              | ''             | 'BE0R0143D00'     |'LED2P_LTL-42FKFDH184T'| 'IO'  | 'LED DIP(2P)ORANGE(LTL-42FKFDH184T)'                                  | ''             | ''          | ''   | '20220207'
 'LED_GREEN'                | 'SMLF'    | 'LTST-C990KGKT-DT'          | 'IC'     | 'BEGR0378Z00'(!)  = ''              | ''             | 'BEGR0378Z00'     |'LED2S_QSMR-C130-QRBC0_H39'| 'IC'  | 'LED SMD(2P) GREEN (LTST-C990KGKT-DT)'                                | ''             | ''          | ''   | '20220301'
 'LED_GREEN'                | 'SMLF'    | 'LTST-C990KGKT-DT'          | 'EMPTY'  | 'BEGR0378Z00'(!)  = ''              | ''             | 'BEGR0378Z00'     |'LED2S_QSMR-C130-QRBC0_H39'| 'IO'  | 'LED SMD(2P) GREEN (LTST-C990KGKT-DT)'                                | ''             | ''          | ''   | '20220301'
 'LED_RED'                  | 'THLF'    | 'LTL-42FEWADHBPT'           | 'IC'     | 'BERD0183Z00'(!)  = ''              | ''             | 'BERD0183Z00'     |'LED2P_LTL-42NEW8DHBPT'| 'IC'  | 'LED DIP(2P)RED (LTL-42FEWADHBPT'                                     | ''             | ''          | ''   | '20220302'
 'LED_RED'                  | 'THLF'    | 'LTL-42FEWADHBPT'           | 'EMPTY'  | 'BERD0183Z00'(!)  = ''              | ''             | 'BERD0183Z00'     |'LED2P_LTL-42NEW8DHBPT'| 'IO'  | 'LED DIP(2P)RED (LTL-42FEWADHBPT'                                     | ''             | ''          | ''   | '20220302'
 'LED_BLUE'                 | 'THLF'    | 'LTLR42FTBGAJH213T'         | 'IC'     | 'BEBL0274D00'(!)  = ''              | ''             | 'BEBL0274D00'     |'LED2P_LTL-42FSVADH213T'| 'IC'  | 'LED DIP(2P)BLUE (LTLR42FTBGAJH213T)'                                 | ''             | ''          | ''   | '20220304'
 'LED_BLUE'                 | 'THLF'    | 'LTLR42FTBGAJH213T'         | 'EMPTY'  | 'BEBL0274D00'(!)  = ''              | ''             | 'BEBL0274D00'     |'LED2P_LTL-42FSVADH213T'| 'IO'  | 'LED DIP(2P)BLUE (LTLR42FTBGAJH213T)'                                 | ''             | ''          | ''   | '20220304'
 'LED2S_SIR57-21C/L294/TR8' | 'SMLF'    | 'SIR57-21C/L294/TR8'        | 'IC'     | 'BE000086ZR0'(!)  = ''              | ''             | 'BE000086ZR0'     |'LED2S_SIR57-21CL388TR8_H160'| 'IC'  | 'LED SMD(2P)INFRARED(SIR57-21C/L294/TR8)'                             | ''             | ''          | ''   | '20220414'
 'LED2S_SIR57-21C/L294/TR8' | 'SMLF'    | 'SIR57-21C/L294/TR8'        | 'EMPTY'  | 'BE000086ZR0'(!)  = ''              | ''             | 'BE000086ZR0'     |'LED2S_SIR57-21CL388TR8_H160'| 'IO'  | 'LED SMD(2P)INFRARED(SIR57-21C/L294/TR8)'                             | ''             | ''          | ''   | '20220414'
 'LED_RED'                  | 'SMLF'    | 'LTST-C191KRKT'             | 'IC'     | 'BERD0065Z00'(!)  = ''              | ''             | 'BERD0065Z00'     |'LED_19217_H22'| 'IC'  | 'LED SMD(2P) RED (LTST-C191KRKT)'                                     | ''             | ''          | ''   | '20220816'
 'LED_RED'                  | 'SMLF'    | 'LTST-C191KRKT'             | 'EMPTY'  | 'BERD0065Z00'(!)  = ''              | ''             | 'BERD0065Z00'     |'LED_19217_H22'| 'IO'  | 'LED SMD(2P) RED (LTST-C191KRKT)'                                     | ''             | ''          | ''   | '20220816'
 'LED_GREEN'                | 'SMLF'    | 'LTST-C191KGKT'             | 'IC'     | 'BEGR0331Z00'(!)  = ''              | ''             | 'BEGR0331Z00'     |'LED_19217_H22'| 'IC'  | 'LED SMD (2P) GREEN (LTST-C191KGKT)'                                  | ''             | ''          | ''   | '20220816'
 'LED_GREEN'                | 'SMLF'    | 'LTST-C191KGKT'             | 'EMPTY'  | 'BEGR0331Z00'(!)  = ''              | ''             | 'BEGR0331Z00'     |'LED_19217_H22'| 'IO'  | 'LED SMD (2P) GREEN (LTST-C191KGKT)'                                  | ''             | ''          | ''   | '20220816'
 'LED_BLUE'                 | 'THLF'    | 'HV-312470/260/SUBD-TR1'    | 'IC'     | 'BEBL0277D00'(!)  = ''              | ''             | 'BEBL0277D00'     |'LED2P_HV-312470260'| 'IC'  | 'LED DIP(2P)BLUE(HV-312470/260/SUBD-TR1)'                             | ''             | ''          | ''   | '20220818'
 'LED_BLUE'                 | 'THLF'    | 'HV-312470/260/SUBD-TR1'    | 'EMPTY'  | 'BEBL0277D00'(!)  = ''              | ''             | 'BEBL0277D00'     |'LED2P_HV-312470260'| 'IO'  | 'LED DIP(2P)BLUE(HV-312470/260/SUBD-TR1)'                             | ''             | ''          | ''   | '20220818'
 'LED_YELLOW'               | 'THLF'    | 'HV-312470/260/UY-TR1'      | 'IC'     | 'BEYL0186D00'(!)  = ''              | ''             | 'BEYL0186D00'     |'LED2P_HV-312470260'| 'IC'  | 'LED DIP(2P)YELLOW(HV-312470/260/UY-TR1)'                             | ''             | ''          | ''   | '20220818'
 'LED_YELLOW'               | 'THLF'    | 'HV-312470/260/UY-TR1'      | 'EMPTY'  | 'BEYL0186D00'(!)  = ''              | ''             | 'BEYL0186D00'     |'LED2P_HV-312470260'| 'IO'  | 'LED DIP(2P)YELLOW(HV-312470/260/UY-TR1)'                             | ''             | ''          | ''   | '20220818'
 'LED2S_LTE-S9511-E-QT'     | 'SMLF'    | 'LTE-S9511-E-QT'            | 'IC'     | 'BE000128ZR0'(!)  = ''              | ''             | 'BE000128ZR0'     |'LED2S_LTE-S9511-E-QT_EOD'| 'IC'  | 'LED SMD(2P)INFRARED(LTE-S9511-E-QT)'                                 | ''             | ''          | ''   | '20221102'
 'LED2S_LTE-S9511-E-QT'     | 'SMLF'    | 'LTE-S9511-E-QT'            | 'EMPTY'  | 'BE000128ZR0'(!)  = ''              | ''             | 'BE000128ZR0'     |'LED2S_LTE-S9511-E-QT_EOD'| 'IO'  | 'LED SMD(2P)INFRARED(LTE-S9511-E-QT)'                                 | ''             | ''          | ''   | '20221102'
 'LED_ORANGE'               | 'SMLF'    | '15-21/S2C-AQ2R2B/3T'       | 'IC'     | 'BE0R0149Z00'(!)  = ''              | ''             | 'BE0R0149Z00'     |'LED2S_15-21S2C-AQ2R2B3T'| 'IC'  | 'LED SMD(2P)ORANGE(15-21/S2C-AQ2R2B/3T)'                              | ''             | ''          | ''   | '20230222'
 'LED_ORANGE'               | 'SMLF'    | '15-21/S2C-AQ2R2B/3T'       | 'EMPTY'  | 'BE0R0149Z00'(!)  = ''              | ''             | 'BE0R0149Z00'     |'LED2S_15-21S2C-AQ2R2B3T'| 'IO'  | 'LED SMD(2P)ORANGE(15-21/S2C-AQ2R2B/3T)'                              | ''             | ''          | ''   | '20230222'
 'LED_ORANGE'               | 'SMLF'    | 'LTST-S482KFKT-SE'          | 'IC'     | 'BE0R0008Z00'(!)  = ''              | ''             | 'BE0R0008Z00'     |'LED2S_LTST-S482KFKT-SE'| 'IC'  | 'LED SMD(2P)ORANGE(LTST-S482KFKT-SE)'                                 | ''             | ''          | ''   | '20230303'
 'LED_ORANGE'               | 'SMLF'    | 'LTST-S482KFKT-SE'          | 'EMPTY'  | 'BE0R0008Z00'(!)  = ''              | ''             | 'BE0R0008Z00'     |'LED2S_LTST-S482KFKT-SE'| 'IO'  | 'LED SMD(2P)ORANGE(LTST-S482KFKT-SE)'                                 | ''             | ''          | ''   | '20230303'
 'LED_ORANGE'               | 'SMLF'    | 'LTST-S482KFKT-Q'           | 'IC'     | 'BE0R0155Z00'(!)  = ''              | ''             | 'BE0R0155Z00'     |'LED2S_LTST-S482KFKT-Q'| 'IC'  | 'LED SMD(2P) ORANGE LTST-S482KFKT-Q'                                  | ''             | ''          | ''   | '20230327'
 'LED_ORANGE'               | 'SMLF'    | 'LTST-S482KFKT-Q'           | 'EMPTY'  | 'BE0R0155Z00'(!)  = ''              | ''             | 'BE0R0155Z00'     |'LED2S_LTST-S482KFKT-Q'| 'IO'  | 'LED SMD(2P) ORANGE LTST-S482KFKT-Q'                                  | ''             | ''          | ''   | '20230327'
 'LED_BLUE'                 | 'THLF'    | 'LTL102TB8WH006PT-Q'        | 'IC'     | 'BEBL0282D00'(!)  = ''              | ''             | 'BEBL0282D00'     |'LED2P_LTL102TB8WH006PT'| 'IC'  | 'LED DIP(2P)BLUE(LTL102TB8WH006PT-Q)'                                 | ''             | ''          | ''   | '20230505'
 'LED_BLUE'                 | 'THLF'    | 'LTL102TB8WH006PT-Q'        | 'EMPTY'  | 'BEBL0282D00'(!)  = ''              | ''             | 'BEBL0282D00'     |'LED2P_LTL102TB8WH006PT'| 'IO'  | 'LED DIP(2P)BLUE(LTL102TB8WH006PT-Q)'                                 | ''             | ''          | ''   | '20230505'
 'LED_GREEN'                | 'THLF'    | 'LTL-533-11P2T-Q'           | 'IC'     | 'BEGR0406D00'(!)  = ''              | ''             | 'BEGR0406D00'     |'LED2P_LTL102TB8WH006PT'| 'IC'  | 'LED DIP(2P)GREEN(LTL-533-11P2T-Q)'                                   | ''             | ''          | ''   | '20230505'
 'LED_GREEN'                | 'THLF'    | 'LTL-533-11P2T-Q'           | 'EMPTY'  | 'BEGR0406D00'(!)  = ''              | ''             | 'BEGR0406D00'     |'LED2P_LTL102TB8WH006PT'| 'IO'  | 'LED DIP(2P)GREEN(LTL-533-11P2T-Q)'                                   | ''             | ''          | ''   | '20230505'
 'LED_ORANGE'               | 'SMLF'    | 'LTST-C190AKT'              | 'IC'     | 'BE0R0096Z00SEL1'(!) = ''              | ''               | 'BE0R0096Z00SEL1' |'LED_1921XA'| 'IC'  | 'LED SMD(2P) ORANGE (LTST-C190AKT)SELA'                               | ''             | ''          | ''   | '20230628'
 'LED_ORANGE'               | 'SMLF'    | 'LTST-C190AKT'              | 'EMPTY'  | 'BE0R0096Z00SEL1'(!) = ''              | ''               | 'BE0R0096Z00SEL1' |'LED_1921XA'| 'IO'  | 'LED SMD(2P) ORANGE (LTST-C190AKT)SELA'                               | ''             | ''          | ''   | '20230628'
 'LED_ORANGE'               | 'SMLF'    | '19-213/S2C-AP2Q2B/3T'      | 'IC'     | 'BE0R0104Z00SEL1'(!) = ''              | ''               | 'BE0R0104Z00SEL1' |'LED_1921'| 'IC'  | 'LED SMD ORANGE(19-213/S2C-AP2Q2B/3T)SELA'                            | ''             | ''          | ''   | '20230628'
 'LED_ORANGE'               | 'SMLF'    | '19-213/S2C-AP2Q2B/3T'      | 'EMPTY'  | 'BE0R0104Z00SEL1'(!) = ''              | ''               | 'BE0R0104Z00SEL1' |'LED_1921'| 'IO'  | 'LED SMD ORANGE(19-213/S2C-AP2Q2B/3T)SELA'                            | ''             | ''          | ''   | '20230628'
 'LED_BLUE'                 | 'SMLF'    | '27-21/BHC-ZM2N2TY/3C'      | 'IC'     | 'BEBL0005Z00SEL1'(!) = ''              | ''               | 'BEBL0005Z00SEL1' |'LED2S_27-21BHC-ZM2N2TY3C'| 'IC'  | 'LEDSMD(2P)BLUE(27-21/BHC-ZM2N2TY/3C)SELA'                            | ''             | ''          | ''   | '20230628'
 'LED_BLUE'                 | 'SMLF'    | '27-21/BHC-ZM2N2TY/3C'      | 'EMPTY'  | 'BEBL0005Z00SEL1'(!) = ''              | ''               | 'BEBL0005Z00SEL1' |'LED2S_27-21BHC-ZM2N2TY3C'| 'IO'  | 'LEDSMD(2P)BLUE(27-21/BHC-ZM2N2TY/3C)SELA'                            | ''             | ''          | ''   | '20230628'
 'LED_GREEN'                | 'SMLF'    | 'LTST-C190KGKT-Q'           | 'IC'     | 'BEGR0100Z08SEL1'(!) = ''              | ''               | 'BEGR0100Z08SEL1' |'LED_1921XA'| 'IC'  | 'LEDSMD(2P)GREEN(LTST-C190KGKT-Q)0603SELA'                            | ''             | ''          | ''   | '20230628'
 'LED_GREEN'                | 'SMLF'    | 'LTST-C190KGKT-Q'           | 'EMPTY'  | 'BEGR0100Z08SEL1'(!) = ''              | ''               | 'BEGR0100Z08SEL1' |'LED_1921XA'| 'IO'  | 'LEDSMD(2P)GREEN(LTST-C190KGKT-Q)0603SELA'                            | ''             | ''          | ''   | '20230628'
 'LED_GREEN'                | 'SMLF'    | '27-21SYGC/S530-E2/TR8'     | 'IC'     | 'BEGR0150Z05SEL1'(!) = ''              | ''               | 'BEGR0150Z05SEL1' |'LED2S_27-21UYC'| 'IC'  | 'LED SMD(2P)GREEN(27-21SYGC/S530-E2)SELA'                             | ''             | ''          | ''   | '20230628'
 'LED_GREEN'                | 'SMLF'    | '27-21SYGC/S530-E2/TR8'     | 'EMPTY'  | 'BEGR0150Z05SEL1'(!) = ''              | ''               | 'BEGR0150Z05SEL1' |'LED2S_27-21UYC'| 'IO'  | 'LED SMD(2P)GREEN(27-21SYGC/S530-E2)SELA'                             | ''             | ''          | ''   | '20230628'
 'LED_GREEN'                | 'SMLF'    | 'LTST-C193KGKT-5A'          | 'IC'     | 'BEGR0272Z00SEL1'(!) = ''              | ''               | 'BEGR0272Z00SEL1' |'LED_19217'| 'IC'  | 'LED SMD(2P)GREEN (LTST-C193KGKT-5A)SELA'                             | ''             | ''          | ''   | '20230628'
 'LED_GREEN'                | 'SMLF'    | 'LTST-C193KGKT-5A'          | 'EMPTY'  | 'BEGR0272Z00SEL1'(!) = ''              | ''               | 'BEGR0272Z00SEL1' |'LED_19217'| 'IO'  | 'LED SMD(2P)GREEN (LTST-C193KGKT-5A)SELA'                             | ''             | ''          | ''   | '20230628'
 'LED_GREEN'                | 'SMLF'    | 'LTST-C281KGKT-5A'          | 'IC'     | 'BEGR0300Z00SEL1'(!) = ''              | ''               | 'BEGR0300Z00SEL1' |'LED2S_0402'| 'IC'  | 'LED SMD(2P) GREEN(LTST-C281KGKT-5A)SELA'                             | ''             | ''          | ''   | '20230628'
 'LED_GREEN'                | 'SMLF'    | 'LTST-C281KGKT-5A'          | 'EMPTY'  | 'BEGR0300Z00SEL1'(!) = ''              | ''               | 'BEGR0300Z00SEL1' |'LED2S_0402'| 'IO'  | 'LED SMD(2P) GREEN(LTST-C281KGKT-5A)SELA'                             | ''             | ''          | ''   | '20230628'
 'LED_RED'                  | 'SMLF'    | 'LTST-C190KRKT'             | 'IC'     | 'BERD0021Z02SEL1'(!) = ''              | ''               | 'BERD0021Z02SEL1' |'LED_1921XA'| 'IC'  | 'LED SMD (2P) RED(LTST-C190KRKT)0603 SELA'                            | ''             | ''          | ''   | '20230628'
 'LED_RED'                  | 'SMLF'    | 'LTST-C190KRKT'             | 'EMPTY'  | 'BERD0021Z02SEL1'(!) = ''              | ''               | 'BERD0021Z02SEL1' |'LED_1921XA'| 'IO'  | 'LED SMD (2P) RED(LTST-C190KRKT)0603 SELA'                            | ''             | ''          | ''   | '20230628'
 'LED_WHITE'                | 'SMLF'    | 'LTW-270TLA'                | 'IC'     | 'BEWH0043Z00SEL1'(!) = ''              | ''               | 'BEWH0043Z00SEL1' |'LED_LTSTS270TBKT'| 'IC'  | 'LED SMD(2P) WHITE(LTW-270TLA)0603SELASN'                             | ''             | ''          | ''   | '20230628'
 'LED_WHITE'                | 'SMLF'    | 'LTW-270TLA'                | 'EMPTY'  | 'BEWH0043Z00SEL1'(!) = ''              | ''               | 'BEWH0043Z00SEL1' |'LED_LTSTS270TBKT'| 'IO'  | 'LED SMD(2P) WHITE(LTW-270TLA)0603SELASN'                             | ''             | ''          | ''   | '20230628'

END_PART

END.

